(kicad_sch (version 20211123) (generator eeschema)

  (paper "A3")

  (title_block
    (title "SA800U (Snapdragon 845) Baseboard")
    (date "2023-10-19")
    (rev "1.0.3")
    (company "Antmicro Ltd.")
    (comment 1 "www.antmicro.com")
  )

  (junction (at 107.95 63.5) (diameter 0) (color 0 0 0 0)
  )
  (junction (at 111.76 203.2) (diameter 0) (color 0 0 0 0)
  )
  (junction (at 78.105 66.04) (diameter 0) (color 0 0 0 0)
  )
  (junction (at 36.83 190.5) (diameter 0) (color 0 0 0 0)
  )
  (junction (at 370.205 42.545) (diameter 0) (color 0 0 0 0)
  )
  (junction (at 74.93 68.58) (diameter 0) (color 0 0 0 0)
  )
  (junction (at 201.295 260.35) (diameter 0) (color 0 0 0 0)
  )
  (junction (at 247.015 125.73) (diameter 0) (color 0 0 0 0)
  )
  (junction (at 159.893 236.855) (diameter 0) (color 0 0 0 0)
  )
  (junction (at 125.984 126.365) (diameter 0) (color 0 0 0 0)
  )
  (junction (at 283.21 125.73) (diameter 0) (color 0 0 0 0)
  )
  (junction (at 245.491 125.73) (diameter 0) (color 0 0 0 0)
  )
  (junction (at 99.822 123.825) (diameter 0) (color 0 0 0 0)
  )
  (junction (at 159.893 244.475) (diameter 0) (color 0 0 0 0)
  )
  (junction (at 36.83 199.39) (diameter 0) (color 0 0 0 0)
  )
  (junction (at 151.765 244.475) (diameter 0) (color 0 0 0 0)
  )
  (junction (at 104.14 223.52) (diameter 0) (color 0 0 0 0)
  )
  (junction (at 53.975 71.12) (diameter 0) (color 0 0 0 0)
  )
  (junction (at 151.765 236.855) (diameter 0) (color 0 0 0 0)
  )
  (junction (at 115.697 259.715) (diameter 0) (color 0 0 0 0)
  )
  (junction (at 254.635 203.835) (diameter 0) (color 0 0 0 0)
  )
  (junction (at 205.74 270.51) (diameter 0) (color 0 0 0 0)
  )
  (junction (at 267.97 125.73) (diameter 0) (color 0 0 0 0)
  )
  (junction (at 75.565 48.895) (diameter 0) (color 0 0 0 0)
  )
  (junction (at 241.935 125.73) (diameter 0) (color 0 0 0 0)
  )
  (junction (at 349.885 212.725) (diameter 0) (color 0 0 0 0)
  )
  (junction (at 96.52 210.82) (diameter 0) (color 0 0 0 0)
  )
  (junction (at 349.25 50.8) (diameter 0) (color 0 0 0 0)
  )
  (junction (at 244.475 196.215) (diameter 0) (color 0 0 0 0)
  )
  (junction (at 26.67 199.39) (diameter 0) (color 0 0 0 0)
  )
  (junction (at 104.775 63.5) (diameter 0) (color 0 0 0 0)
  )
  (junction (at 115.57 254.635) (diameter 0) (color 0 0 0 0)
  )
  (junction (at 118.11 190.5) (diameter 0) (color 0 0 0 0)
  )
  (junction (at 314.325 212.725) (diameter 0) (color 0 0 0 0)
  )
  (junction (at 347.345 233.045) (diameter 0) (color 0 0 0 0)
  )
  (junction (at 91.44 159.385) (diameter 0) (color 0 0 0 0)
  )
  (junction (at 104.14 207.01) (diameter 0) (color 0 0 0 0)
  )
  (junction (at 212.725 125.73) (diameter 0) (color 0 0 0 0)
  )
  (junction (at 26.67 190.5) (diameter 0) (color 0 0 0 0)
  )
  (junction (at 103.378 144.526) (diameter 0) (color 0 0 0 0)
  )
  (junction (at 111.76 66.04) (diameter 0) (color 0 0 0 0)
  )
  (junction (at 346.71 87.63) (diameter 0) (color 0 0 0 0)
  )
  (junction (at 109.982 123.825) (diameter 0) (color 0 0 0 0)
  )
  (junction (at 113.665 236.855) (diameter 0) (color 0 0 0 0)
  )
  (junction (at 316.865 233.045) (diameter 0) (color 0 0 0 0)
  )
  (junction (at 64.77 215.9) (diameter 0) (color 0 0 0 0)
  )
  (junction (at 316.23 87.63) (diameter 0) (color 0 0 0 0)
  )
  (junction (at 91.44 164.465) (diameter 0) (color 0 0 0 0)
  )
  (junction (at 115.443 249.555) (diameter 0) (color 0 0 0 0)
  )
  (junction (at 53.975 66.04) (diameter 0) (color 0 0 0 0)
  )
  (junction (at 111.76 223.52) (diameter 0) (color 0 0 0 0)
  )
  (junction (at 44.577 128.905) (diameter 0) (color 0 0 0 0)
  )
  (junction (at 91.44 161.925) (diameter 0) (color 0 0 0 0)
  )
  (junction (at 313.69 67.31) (diameter 0) (color 0 0 0 0)
  )
  (junction (at 44.577 126.365) (diameter 0) (color 0 0 0 0)
  )
  (junction (at 349.25 67.31) (diameter 0) (color 0 0 0 0)
  )
  (junction (at 380.365 50.165) (diameter 0) (color 0 0 0 0)
  )
  (junction (at 113.665 244.475) (diameter 0) (color 0 0 0 0)
  )
  (junction (at 93.472 126.365) (diameter 0) (color 0 0 0 0)
  )
  (junction (at 314.325 196.215) (diameter 0) (color 0 0 0 0)
  )
  (junction (at 113.538 141.986) (diameter 0) (color 0 0 0 0)
  )

  (no_connect (at 344.043 133.35))
  (no_connect (at 343.408 215.265))
  (no_connect (at 321.183 156.21))
  (no_connect (at 64.516 156.845))
  (no_connect (at 64.516 139.065))
  (no_connect (at 64.516 146.685))
  (no_connect (at 112.395 264.795))
  (no_connect (at 320.548 222.885))
  (no_connect (at 160.02 77.47))
  (no_connect (at 321.183 148.59))
  (no_connect (at 344.043 140.97))
  (no_connect (at 64.516 149.225))
  (no_connect (at 344.043 156.21))
  (no_connect (at 64.516 151.765))
  (no_connect (at 344.043 148.59))
  (no_connect (at 64.516 144.145))
  (no_connect (at 64.516 141.605))
  (no_connect (at 344.043 153.67))
  (no_connect (at 344.043 135.89))
  (no_connect (at 64.516 154.305))
  (no_connect (at 280.035 258.445))
  (no_connect (at 64.516 133.985))
  (no_connect (at 89.916 151.765))
  (no_connect (at 92.075 264.795))
  (no_connect (at 167.64 77.47))
  (no_connect (at 321.183 135.89))
  (no_connect (at 321.183 133.35))
  (no_connect (at 89.916 128.905))
  (no_connect (at 321.183 153.67))
  (no_connect (at 64.516 131.445))
  (no_connect (at 321.183 140.97))
  (no_connect (at 89.916 154.305))
  (no_connect (at 282.575 258.445))
  (no_connect (at 64.516 159.385))

  (wire (pts (xy 221.488 128.27) (xy 219.075 128.27))
    (stroke (width 0) (type default) (color 0 0 0 0))
  )
  (wire (pts (xy 221.488 125.73) (xy 212.725 125.73))
    (stroke (width 0) (type default) (color 0 0 0 0))
  )
  (wire (pts (xy 295.275 125.73) (xy 283.21 125.73))
    (stroke (width 0) (type default) (color 0 0 0 0))
  )
  (wire (pts (xy 264.795 210.185) (xy 284.226 210.185))
    (stroke (width 0) (type default) (color 0 0 0 0))
  )
  (wire (pts (xy 112.395 249.555) (xy 115.443 249.555))
    (stroke (width 0) (type default) (color 0 0 0 0))
  )
  (wire (pts (xy 201.295 260.35) (xy 207.01 260.35))
    (stroke (width 0) (type default) (color 0 0 0 0))
  )
  (wire (pts (xy 239.395 73.025) (xy 239.395 77.47))
    (stroke (width 0) (type default) (color 0 0 0 0))
  )
  (wire (pts (xy 343.408 230.505) (xy 371.221 230.505))
    (stroke (width 0) (type default) (color 0 0 0 0))
  )
  (wire (pts (xy 113.665 236.22) (xy 113.665 236.855))
    (stroke (width 0) (type default) (color 0 0 0 0))
  )
  (wire (pts (xy 375.539 64.77) (xy 387.35 64.77))
    (stroke (width 0) (type default) (color 0 0 0 0))
  )
  (wire (pts (xy 149.86 76.2) (xy 149.86 80.645))
    (stroke (width 0) (type default) (color 0 0 0 0))
  )
  (wire (pts (xy 342.773 87.63) (xy 346.71 87.63))
    (stroke (width 0) (type default) (color 0 0 0 0))
  )
  (wire (pts (xy 316.23 87.63) (xy 316.23 59.69))
    (stroke (width 0) (type default) (color 0 0 0 0))
  )
  (wire (pts (xy 342.773 69.85) (xy 403.86 69.85))
    (stroke (width 0) (type default) (color 0 0 0 0))
  )
  (wire (pts (xy 347.345 205.105) (xy 347.345 233.045))
    (stroke (width 0) (type default) (color 0 0 0 0))
  )
  (wire (pts (xy 113.538 141.986) (xy 128.778 141.986))
    (stroke (width 0) (type default) (color 0 0 0 0))
  )
  (wire (pts (xy 53.975 80.645) (xy 53.975 78.994))
    (stroke (width 0) (type default) (color 0 0 0 0))
  )
  (wire (pts (xy 64.77 205.74) (xy 64.77 209.169))
    (stroke (width 0) (type default) (color 0 0 0 0))
  )
  (wire (pts (xy 205.74 270.51) (xy 207.01 270.51))
    (stroke (width 0) (type default) (color 0 0 0 0))
  )
  (wire (pts (xy 376.301 230.505) (xy 400.05 230.505))
    (stroke (width 0) (type default) (color 0 0 0 0))
  )
  (wire (pts (xy 199.39 246.38) (xy 207.01 246.38))
    (stroke (width 0) (type default) (color 0 0 0 0))
  )
  (wire (pts (xy 111.76 223.52) (xy 111.76 220.218))
    (stroke (width 0) (type default) (color 0 0 0 0))
  )
  (polyline (pts (xy 407.035 34.29) (xy 13.335 34.29))
    (stroke (width 0) (type default) (color 0 0 0 0))
  )

  (wire (pts (xy 104.775 50.165) (xy 104.775 49.022))
    (stroke (width 0) (type default) (color 0 0 0 0))
  )
  (wire (pts (xy 117.475 236.855) (xy 113.665 236.855))
    (stroke (width 0) (type default) (color 0 0 0 0))
  )
  (wire (pts (xy 56.515 195.58) (xy 73.66 195.58))
    (stroke (width 0) (type default) (color 0 0 0 0))
  )
  (polyline (pts (xy 406.4 177.8) (xy 12.7 177.8))
    (stroke (width 0) (type default) (color 0 0 0 0))
  )

  (wire (pts (xy 286.385 230.505) (xy 264.795 230.505))
    (stroke (width 0) (type default) (color 0 0 0 0))
  )
  (wire (pts (xy 159.893 236.855) (xy 159.893 238.252))
    (stroke (width 0) (type default) (color 0 0 0 0))
  )
  (wire (pts (xy 44.577 126.365) (xy 64.516 126.365))
    (stroke (width 0) (type default) (color 0 0 0 0))
  )
  (wire (pts (xy 344.043 146.05) (xy 359.41 146.05))
    (stroke (width 0) (type default) (color 0 0 0 0))
  )
  (wire (pts (xy 39.37 66.04) (xy 31.75 66.04))
    (stroke (width 0) (type default) (color 0 0 0 0))
  )
  (wire (pts (xy 224.79 65.405) (xy 247.015 65.405))
    (stroke (width 0) (type default) (color 0 0 0 0))
  )
  (wire (pts (xy 93.98 190.5) (xy 118.11 190.5))
    (stroke (width 0) (type default) (color 0 0 0 0))
  )
  (wire (pts (xy 80.01 66.04) (xy 78.105 66.04))
    (stroke (width 0) (type default) (color 0 0 0 0))
  )
  (wire (pts (xy 273.685 147.955) (xy 273.685 149.225))
    (stroke (width 0) (type default) (color 0 0 0 0))
  )
  (wire (pts (xy 86.995 244.475) (xy 92.075 244.475))
    (stroke (width 0) (type default) (color 0 0 0 0))
  )
  (wire (pts (xy 314.325 212.725) (xy 314.325 196.215))
    (stroke (width 0) (type default) (color 0 0 0 0))
  )
  (wire (pts (xy 349.25 80.01) (xy 349.25 67.31))
    (stroke (width 0) (type default) (color 0 0 0 0))
  )
  (wire (pts (xy 269.875 257.175) (xy 277.495 257.175))
    (stroke (width 0) (type default) (color 0 0 0 0))
  )
  (wire (pts (xy 184.785 77.47) (xy 184.785 76.2))
    (stroke (width 0) (type default) (color 0 0 0 0))
  )
  (wire (pts (xy 234.315 196.215) (xy 244.475 196.215))
    (stroke (width 0) (type default) (color 0 0 0 0))
  )
  (wire (pts (xy 217.805 77.47) (xy 217.805 67.945))
    (stroke (width 0) (type default) (color 0 0 0 0))
  )
  (wire (pts (xy 236.728 128.27) (xy 241.935 128.27))
    (stroke (width 0) (type default) (color 0 0 0 0))
  )
  (wire (pts (xy 285.75 85.09) (xy 275.59 85.09))
    (stroke (width 0) (type default) (color 0 0 0 0))
  )
  (wire (pts (xy 232.41 246.38) (xy 246.38 246.38))
    (stroke (width 0) (type default) (color 0 0 0 0))
  )
  (wire (pts (xy 177.165 76.2) (xy 177.165 80.645))
    (stroke (width 0) (type default) (color 0 0 0 0))
  )
  (wire (pts (xy 201.295 260.35) (xy 201.295 266.7))
    (stroke (width 0) (type default) (color 0 0 0 0))
  )
  (wire (pts (xy 316.865 233.045) (xy 316.865 205.105))
    (stroke (width 0) (type default) (color 0 0 0 0))
  )
  (wire (pts (xy 245.491 124.46) (xy 245.491 125.73))
    (stroke (width 0) (type default) (color 0 0 0 0))
  )
  (wire (pts (xy 183.515 67.945) (xy 192.405 67.945))
    (stroke (width 0) (type default) (color 0 0 0 0))
  )
  (wire (pts (xy 53.975 66.04) (xy 53.975 63.754))
    (stroke (width 0) (type default) (color 0 0 0 0))
  )
  (wire (pts (xy 346.71 158.75) (xy 346.71 160.02))
    (stroke (width 0) (type default) (color 0 0 0 0))
  )
  (wire (pts (xy 26.67 190.5) (xy 26.67 191.77))
    (stroke (width 0) (type default) (color 0 0 0 0))
  )
  (wire (pts (xy 344.043 158.75) (xy 346.71 158.75))
    (stroke (width 0) (type default) (color 0 0 0 0))
  )
  (wire (pts (xy 89.916 164.465) (xy 91.44 164.465))
    (stroke (width 0) (type default) (color 0 0 0 0))
  )
  (wire (pts (xy 400.05 210.185) (xy 376.428 210.185))
    (stroke (width 0) (type default) (color 0 0 0 0))
  )
  (wire (pts (xy 281.305 140.97) (xy 281.305 149.225))
    (stroke (width 0) (type default) (color 0 0 0 0))
  )
  (wire (pts (xy 192.405 67.945) (xy 192.405 77.47))
    (stroke (width 0) (type default) (color 0 0 0 0))
  )
  (wire (pts (xy 104.14 207.01) (xy 104.14 215.138))
    (stroke (width 0) (type default) (color 0 0 0 0))
  )
  (wire (pts (xy 294.259 62.23) (xy 319.913 62.23))
    (stroke (width 0) (type default) (color 0 0 0 0))
  )
  (wire (pts (xy 74.93 68.58) (xy 80.01 68.58))
    (stroke (width 0) (type default) (color 0 0 0 0))
  )
  (wire (pts (xy 277.495 251.46) (xy 287.655 251.46))
    (stroke (width 0) (type default) (color 0 0 0 0))
  )
  (polyline (pts (xy 407.035 108.585) (xy 13.335 108.585))
    (stroke (width 0) (type default) (color 0 0 0 0))
  )

  (wire (pts (xy 25.4 190.5) (xy 26.67 190.5))
    (stroke (width 0) (type default) (color 0 0 0 0))
  )
  (wire (pts (xy 89.662 269.875) (xy 92.075 269.875))
    (stroke (width 0) (type default) (color 0 0 0 0))
  )
  (wire (pts (xy 73.66 215.9) (xy 73.66 210.82))
    (stroke (width 0) (type default) (color 0 0 0 0))
  )
  (wire (pts (xy 94.996 144.526) (xy 103.378 144.526))
    (stroke (width 0) (type default) (color 0 0 0 0))
  )
  (wire (pts (xy 26.67 199.39) (xy 26.67 200.66))
    (stroke (width 0) (type default) (color 0 0 0 0))
  )
  (wire (pts (xy 349.25 50.8) (xy 313.69 50.8))
    (stroke (width 0) (type default) (color 0 0 0 0))
  )
  (wire (pts (xy 91.44 159.385) (xy 89.916 159.385))
    (stroke (width 0) (type default) (color 0 0 0 0))
  )
  (wire (pts (xy 112.395 259.715) (xy 115.697 259.715))
    (stroke (width 0) (type default) (color 0 0 0 0))
  )
  (wire (pts (xy 343.408 207.645) (xy 373.888 207.645))
    (stroke (width 0) (type default) (color 0 0 0 0))
  )
  (wire (pts (xy 197.485 65.405) (xy 220.345 65.405))
    (stroke (width 0) (type default) (color 0 0 0 0))
  )
  (wire (pts (xy 359.41 138.43) (xy 344.043 138.43))
    (stroke (width 0) (type default) (color 0 0 0 0))
  )
  (wire (pts (xy 342.773 74.93) (xy 394.335 74.93))
    (stroke (width 0) (type default) (color 0 0 0 0))
  )
  (wire (pts (xy 107.95 62.865) (xy 107.95 63.5))
    (stroke (width 0) (type default) (color 0 0 0 0))
  )
  (wire (pts (xy 313.69 67.31) (xy 313.69 50.8))
    (stroke (width 0) (type default) (color 0 0 0 0))
  )
  (wire (pts (xy 115.443 249.047) (xy 115.443 249.555))
    (stroke (width 0) (type default) (color 0 0 0 0))
  )
  (wire (pts (xy 349.885 225.425) (xy 349.885 212.725))
    (stroke (width 0) (type default) (color 0 0 0 0))
  )
  (wire (pts (xy 118.11 190.5) (xy 118.11 191.516))
    (stroke (width 0) (type default) (color 0 0 0 0))
  )
  (wire (pts (xy 316.865 205.105) (xy 320.548 205.105))
    (stroke (width 0) (type default) (color 0 0 0 0))
  )
  (wire (pts (xy 247.015 125.73) (xy 245.491 125.73))
    (stroke (width 0) (type default) (color 0 0 0 0))
  )
  (wire (pts (xy 53.975 58.674) (xy 53.975 55.88))
    (stroke (width 0) (type default) (color 0 0 0 0))
  )
  (wire (pts (xy 384.175 223.52) (xy 400.05 223.52))
    (stroke (width 0) (type default) (color 0 0 0 0))
  )
  (wire (pts (xy 343.408 212.725) (xy 349.885 212.725))
    (stroke (width 0) (type default) (color 0 0 0 0))
  )
  (wire (pts (xy 93.98 207.01) (xy 104.14 207.01))
    (stroke (width 0) (type default) (color 0 0 0 0))
  )
  (wire (pts (xy 349.885 196.215) (xy 314.325 196.215))
    (stroke (width 0) (type default) (color 0 0 0 0))
  )
  (wire (pts (xy 266.065 140.97) (xy 281.305 140.97))
    (stroke (width 0) (type default) (color 0 0 0 0))
  )
  (wire (pts (xy 247.015 77.47) (xy 247.015 65.405))
    (stroke (width 0) (type default) (color 0 0 0 0))
  )
  (wire (pts (xy 113.665 244.475) (xy 113.665 269.875))
    (stroke (width 0) (type default) (color 0 0 0 0))
  )
  (wire (pts (xy 346.71 59.69) (xy 346.71 87.63))
    (stroke (width 0) (type default) (color 0 0 0 0))
  )
  (wire (pts (xy 306.07 143.51) (xy 321.183 143.51))
    (stroke (width 0) (type default) (color 0 0 0 0))
  )
  (wire (pts (xy 199.39 251.46) (xy 207.01 251.46))
    (stroke (width 0) (type default) (color 0 0 0 0))
  )
  (wire (pts (xy 342.773 67.31) (xy 349.25 67.31))
    (stroke (width 0) (type default) (color 0 0 0 0))
  )
  (wire (pts (xy 220.345 77.47) (xy 220.345 65.405))
    (stroke (width 0) (type default) (color 0 0 0 0))
  )
  (wire (pts (xy 294.005 227.965) (xy 320.548 227.965))
    (stroke (width 0) (type default) (color 0 0 0 0))
  )
  (wire (pts (xy 103.378 144.526) (xy 103.378 145.161))
    (stroke (width 0) (type default) (color 0 0 0 0))
  )
  (wire (pts (xy 39.37 71.12) (xy 31.75 71.12))
    (stroke (width 0) (type default) (color 0 0 0 0))
  )
  (wire (pts (xy 280.035 217.805) (xy 320.548 217.805))
    (stroke (width 0) (type default) (color 0 0 0 0))
  )
  (wire (pts (xy 53.975 66.04) (xy 44.45 66.04))
    (stroke (width 0) (type default) (color 0 0 0 0))
  )
  (wire (pts (xy 115.697 259.715) (xy 125.222 259.715))
    (stroke (width 0) (type default) (color 0 0 0 0))
  )
  (wire (pts (xy 205.74 265.43) (xy 205.74 270.51))
    (stroke (width 0) (type default) (color 0 0 0 0))
  )
  (wire (pts (xy 159.893 236.855) (xy 169.418 236.855))
    (stroke (width 0) (type default) (color 0 0 0 0))
  )
  (wire (pts (xy 320.548 212.725) (xy 314.325 212.725))
    (stroke (width 0) (type default) (color 0 0 0 0))
  )
  (wire (pts (xy 344.043 130.81) (xy 347.98 130.81))
    (stroke (width 0) (type default) (color 0 0 0 0))
  )
  (wire (pts (xy 197.485 67.945) (xy 217.805 67.945))
    (stroke (width 0) (type default) (color 0 0 0 0))
  )
  (wire (pts (xy 315.595 158.75) (xy 321.183 158.75))
    (stroke (width 0) (type default) (color 0 0 0 0))
  )
  (wire (pts (xy 285.115 254) (xy 285.115 258.445))
    (stroke (width 0) (type default) (color 0 0 0 0))
  )
  (wire (pts (xy 107.95 198.12) (xy 93.98 198.12))
    (stroke (width 0) (type default) (color 0 0 0 0))
  )
  (wire (pts (xy 344.043 143.51) (xy 359.41 143.51))
    (stroke (width 0) (type default) (color 0 0 0 0))
  )
  (wire (pts (xy 241.935 125.73) (xy 236.728 125.73))
    (stroke (width 0) (type default) (color 0 0 0 0))
  )
  (wire (pts (xy 159.893 243.332) (xy 159.893 244.475))
    (stroke (width 0) (type default) (color 0 0 0 0))
  )
  (wire (pts (xy 26.67 196.85) (xy 26.67 199.39))
    (stroke (width 0) (type default) (color 0 0 0 0))
  )
  (wire (pts (xy 75.565 48.895) (xy 100.457 48.895))
    (stroke (width 0) (type default) (color 0 0 0 0))
  )
  (wire (pts (xy 254.635 203.835) (xy 244.475 203.835))
    (stroke (width 0) (type default) (color 0 0 0 0))
  )
  (wire (pts (xy 76.2 249.555) (xy 92.075 249.555))
    (stroke (width 0) (type default) (color 0 0 0 0))
  )
  (wire (pts (xy 315.595 158.75) (xy 315.595 160.02))
    (stroke (width 0) (type default) (color 0 0 0 0))
  )
  (wire (pts (xy 314.325 225.425) (xy 314.325 212.725))
    (stroke (width 0) (type default) (color 0 0 0 0))
  )
  (wire (pts (xy 183.515 65.405) (xy 194.945 65.405))
    (stroke (width 0) (type default) (color 0 0 0 0))
  )
  (wire (pts (xy 36.83 190.5) (xy 46.99 190.5))
    (stroke (width 0) (type default) (color 0 0 0 0))
  )
  (wire (pts (xy 271.145 78.74) (xy 271.145 77.47))
    (stroke (width 0) (type default) (color 0 0 0 0))
  )
  (wire (pts (xy 241.935 70.485) (xy 241.935 77.47))
    (stroke (width 0) (type default) (color 0 0 0 0))
  )
  (wire (pts (xy 343.408 220.345) (xy 384.81 220.345))
    (stroke (width 0) (type default) (color 0 0 0 0))
  )
  (wire (pts (xy 343.408 217.805) (xy 384.81 217.805))
    (stroke (width 0) (type default) (color 0 0 0 0))
  )
  (wire (pts (xy 91.44 159.385) (xy 91.44 161.925))
    (stroke (width 0) (type default) (color 0 0 0 0))
  )
  (wire (pts (xy 232.41 248.92) (xy 246.38 248.92))
    (stroke (width 0) (type default) (color 0 0 0 0))
  )
  (wire (pts (xy 76.2 254.635) (xy 92.075 254.635))
    (stroke (width 0) (type default) (color 0 0 0 0))
  )
  (wire (pts (xy 54.229 123.825) (xy 64.516 123.825))
    (stroke (width 0) (type default) (color 0 0 0 0))
  )
  (wire (pts (xy 36.83 191.77) (xy 36.83 190.5))
    (stroke (width 0) (type default) (color 0 0 0 0))
  )
  (wire (pts (xy 111.76 203.2) (xy 134.62 203.2))
    (stroke (width 0) (type default) (color 0 0 0 0))
  )
  (wire (pts (xy 36.83 196.85) (xy 36.83 199.39))
    (stroke (width 0) (type default) (color 0 0 0 0))
  )
  (wire (pts (xy 159.893 244.475) (xy 169.418 244.475))
    (stroke (width 0) (type default) (color 0 0 0 0))
  )
  (wire (pts (xy 97.79 60.96) (xy 100.457 60.96))
    (stroke (width 0) (type default) (color 0 0 0 0))
  )
  (wire (pts (xy 316.865 233.045) (xy 316.865 243.205))
    (stroke (width 0) (type default) (color 0 0 0 0))
  )
  (wire (pts (xy 93.98 203.2) (xy 111.76 203.2))
    (stroke (width 0) (type default) (color 0 0 0 0))
  )
  (wire (pts (xy 306.07 146.05) (xy 321.183 146.05))
    (stroke (width 0) (type default) (color 0 0 0 0))
  )
  (wire (pts (xy 104.14 220.218) (xy 104.14 223.52))
    (stroke (width 0) (type default) (color 0 0 0 0))
  )
  (wire (pts (xy 320.548 225.425) (xy 314.325 225.425))
    (stroke (width 0) (type default) (color 0 0 0 0))
  )
  (wire (pts (xy 112.395 269.875) (xy 113.665 269.875))
    (stroke (width 0) (type default) (color 0 0 0 0))
  )
  (wire (pts (xy 316.23 59.69) (xy 319.913 59.69))
    (stroke (width 0) (type default) (color 0 0 0 0))
  )
  (wire (pts (xy 60.325 236.855) (xy 60.325 238.76))
    (stroke (width 0) (type default) (color 0 0 0 0))
  )
  (wire (pts (xy 91.44 165.862) (xy 91.44 164.465))
    (stroke (width 0) (type default) (color 0 0 0 0))
  )
  (wire (pts (xy 46.99 191.77) (xy 46.99 190.5))
    (stroke (width 0) (type default) (color 0 0 0 0))
  )
  (wire (pts (xy 93.98 195.58) (xy 107.95 195.58))
    (stroke (width 0) (type default) (color 0 0 0 0))
  )
  (wire (pts (xy 306.07 151.13) (xy 321.183 151.13))
    (stroke (width 0) (type default) (color 0 0 0 0))
  )
  (wire (pts (xy 74.93 71.12) (xy 53.975 71.12))
    (stroke (width 0) (type default) (color 0 0 0 0))
  )
  (wire (pts (xy 269.875 74.93) (xy 319.913 74.93))
    (stroke (width 0) (type default) (color 0 0 0 0))
  )
  (wire (pts (xy 232.41 238.76) (xy 246.38 238.76))
    (stroke (width 0) (type default) (color 0 0 0 0))
  )
  (wire (pts (xy 370.205 42.545) (xy 380.365 42.545))
    (stroke (width 0) (type default) (color 0 0 0 0))
  )
  (wire (pts (xy 378.968 207.645) (xy 400.05 207.645))
    (stroke (width 0) (type default) (color 0 0 0 0))
  )
  (wire (pts (xy 291.465 230.505) (xy 320.548 230.505))
    (stroke (width 0) (type default) (color 0 0 0 0))
  )
  (wire (pts (xy 288.925 227.965) (xy 264.795 227.965))
    (stroke (width 0) (type default) (color 0 0 0 0))
  )
  (wire (pts (xy 204.597 76.2) (xy 210.185 76.2))
    (stroke (width 0) (type default) (color 0 0 0 0))
  )
  (wire (pts (xy 96.52 210.82) (xy 134.62 210.82))
    (stroke (width 0) (type default) (color 0 0 0 0))
  )
  (wire (pts (xy 380.365 48.895) (xy 380.365 50.165))
    (stroke (width 0) (type default) (color 0 0 0 0))
  )
  (wire (pts (xy 212.725 125.73) (xy 212.725 127.635))
    (stroke (width 0) (type default) (color 0 0 0 0))
  )
  (wire (pts (xy 115.57 71.12) (xy 97.79 71.12))
    (stroke (width 0) (type default) (color 0 0 0 0))
  )
  (wire (pts (xy 113.538 141.986) (xy 113.538 145.161))
    (stroke (width 0) (type default) (color 0 0 0 0))
  )
  (wire (pts (xy 319.913 87.63) (xy 316.23 87.63))
    (stroke (width 0) (type default) (color 0 0 0 0))
  )
  (wire (pts (xy 343.408 225.425) (xy 349.885 225.425))
    (stroke (width 0) (type default) (color 0 0 0 0))
  )
  (wire (pts (xy 244.475 196.215) (xy 254.635 196.215))
    (stroke (width 0) (type default) (color 0 0 0 0))
  )
  (wire (pts (xy 89.916 136.525) (xy 94.996 136.525))
    (stroke (width 0) (type default) (color 0 0 0 0))
  )
  (wire (pts (xy 112.395 244.475) (xy 113.665 244.475))
    (stroke (width 0) (type default) (color 0 0 0 0))
  )
  (wire (pts (xy 162.56 77.47) (xy 162.56 73.66))
    (stroke (width 0) (type default) (color 0 0 0 0))
  )
  (wire (pts (xy 57.15 200.66) (xy 57.15 201.93))
    (stroke (width 0) (type default) (color 0 0 0 0))
  )
  (wire (pts (xy 370.205 42.545) (xy 370.205 43.815))
    (stroke (width 0) (type default) (color 0 0 0 0))
  )
  (wire (pts (xy 96.52 220.218) (xy 96.52 223.52))
    (stroke (width 0) (type default) (color 0 0 0 0))
  )
  (wire (pts (xy 75.565 50.165) (xy 75.565 48.895))
    (stroke (width 0) (type default) (color 0 0 0 0))
  )
  (wire (pts (xy 266.065 147.955) (xy 273.685 147.955))
    (stroke (width 0) (type default) (color 0 0 0 0))
  )
  (wire (pts (xy 244.475 196.215) (xy 244.475 197.485))
    (stroke (width 0) (type default) (color 0 0 0 0))
  )
  (wire (pts (xy 44.577 129.794) (xy 44.577 128.905))
    (stroke (width 0) (type default) (color 0 0 0 0))
  )
  (wire (pts (xy 113.665 236.855) (xy 113.665 244.475))
    (stroke (width 0) (type default) (color 0 0 0 0))
  )
  (wire (pts (xy 104.775 55.245) (xy 104.775 63.5))
    (stroke (width 0) (type default) (color 0 0 0 0))
  )
  (wire (pts (xy 276.225 146.05) (xy 276.225 149.225))
    (stroke (width 0) (type default) (color 0 0 0 0))
  )
  (wire (pts (xy 224.79 73.025) (xy 239.395 73.025))
    (stroke (width 0) (type default) (color 0 0 0 0))
  )
  (wire (pts (xy 267.97 125.73) (xy 272.796 125.73))
    (stroke (width 0) (type default) (color 0 0 0 0))
  )
  (wire (pts (xy 64.77 214.249) (xy 64.77 215.9))
    (stroke (width 0) (type default) (color 0 0 0 0))
  )
  (wire (pts (xy 316.23 87.63) (xy 316.23 97.79))
    (stroke (width 0) (type default) (color 0 0 0 0))
  )
  (wire (pts (xy 111.76 66.04) (xy 116.332 66.04))
    (stroke (width 0) (type default) (color 0 0 0 0))
  )
  (wire (pts (xy 384.175 222.885) (xy 384.175 223.52))
    (stroke (width 0) (type default) (color 0 0 0 0))
  )
  (wire (pts (xy 266.065 138.43) (xy 283.845 138.43))
    (stroke (width 0) (type default) (color 0 0 0 0))
  )
  (wire (pts (xy 57.15 200.66) (xy 73.66 200.66))
    (stroke (width 0) (type default) (color 0 0 0 0))
  )
  (wire (pts (xy 289.306 210.185) (xy 320.548 210.185))
    (stroke (width 0) (type default) (color 0 0 0 0))
  )
  (wire (pts (xy 291.719 64.77) (xy 319.913 64.77))
    (stroke (width 0) (type default) (color 0 0 0 0))
  )
  (wire (pts (xy 215.265 70.485) (xy 215.265 77.47))
    (stroke (width 0) (type default) (color 0 0 0 0))
  )
  (wire (pts (xy 264.795 196.215) (xy 314.325 196.215))
    (stroke (width 0) (type default) (color 0 0 0 0))
  )
  (wire (pts (xy 317.5 130.81) (xy 321.183 130.81))
    (stroke (width 0) (type default) (color 0 0 0 0))
  )
  (wire (pts (xy 78.105 71.12) (xy 78.105 66.04))
    (stroke (width 0) (type default) (color 0 0 0 0))
  )
  (wire (pts (xy 205.74 270.51) (xy 205.74 271.78))
    (stroke (width 0) (type default) (color 0 0 0 0))
  )
  (wire (pts (xy 52.705 55.88) (xy 53.975 55.88))
    (stroke (width 0) (type default) (color 0 0 0 0))
  )
  (wire (pts (xy 103.378 144.526) (xy 128.778 144.526))
    (stroke (width 0) (type default) (color 0 0 0 0))
  )
  (wire (pts (xy 99.822 119.38) (xy 99.822 123.825))
    (stroke (width 0) (type default) (color 0 0 0 0))
  )
  (wire (pts (xy 38.227 128.905) (xy 44.577 128.905))
    (stroke (width 0) (type default) (color 0 0 0 0))
  )
  (wire (pts (xy 283.21 125.73) (xy 277.876 125.73))
    (stroke (width 0) (type default) (color 0 0 0 0))
  )
  (wire (pts (xy 151.765 236.855) (xy 151.765 238.252))
    (stroke (width 0) (type default) (color 0 0 0 0))
  )
  (wire (pts (xy 247.015 127.635) (xy 247.015 125.73))
    (stroke (width 0) (type default) (color 0 0 0 0))
  )
  (wire (pts (xy 212.725 73.025) (xy 212.725 77.47))
    (stroke (width 0) (type default) (color 0 0 0 0))
  )
  (wire (pts (xy 80.01 63.5) (xy 74.93 63.5))
    (stroke (width 0) (type default) (color 0 0 0 0))
  )
  (wire (pts (xy 320.548 233.045) (xy 316.865 233.045))
    (stroke (width 0) (type default) (color 0 0 0 0))
  )
  (wire (pts (xy 247.015 125.73) (xy 267.97 125.73))
    (stroke (width 0) (type default) (color 0 0 0 0))
  )
  (wire (pts (xy 93.472 122.555) (xy 93.472 126.365))
    (stroke (width 0) (type default) (color 0 0 0 0))
  )
  (wire (pts (xy 197.485 73.025) (xy 212.725 73.025))
    (stroke (width 0) (type default) (color 0 0 0 0))
  )
  (wire (pts (xy 241.935 128.27) (xy 241.935 125.73))
    (stroke (width 0) (type default) (color 0 0 0 0))
  )
  (wire (pts (xy 277.495 254) (xy 285.115 254))
    (stroke (width 0) (type default) (color 0 0 0 0))
  )
  (wire (pts (xy 183.515 70.485) (xy 189.865 70.485))
    (stroke (width 0) (type default) (color 0 0 0 0))
  )
  (wire (pts (xy 359.41 151.13) (xy 344.043 151.13))
    (stroke (width 0) (type default) (color 0 0 0 0))
  )
  (wire (pts (xy 342.773 72.39) (xy 394.335 72.39))
    (stroke (width 0) (type default) (color 0 0 0 0))
  )
  (wire (pts (xy 115.57 254.635) (xy 125.222 254.635))
    (stroke (width 0) (type default) (color 0 0 0 0))
  )
  (wire (pts (xy 378.079 62.23) (xy 387.35 62.23))
    (stroke (width 0) (type default) (color 0 0 0 0))
  )
  (wire (pts (xy 64.77 190.5) (xy 73.66 190.5))
    (stroke (width 0) (type default) (color 0 0 0 0))
  )
  (wire (pts (xy 372.999 82.55) (xy 342.773 82.55))
    (stroke (width 0) (type default) (color 0 0 0 0))
  )
  (wire (pts (xy 264.795 215.265) (xy 320.548 215.265))
    (stroke (width 0) (type default) (color 0 0 0 0))
  )
  (wire (pts (xy 44.577 128.905) (xy 64.516 128.905))
    (stroke (width 0) (type default) (color 0 0 0 0))
  )
  (wire (pts (xy 157.48 77.47) (xy 157.48 76.2))
    (stroke (width 0) (type default) (color 0 0 0 0))
  )
  (wire (pts (xy 346.71 87.63) (xy 346.71 97.79))
    (stroke (width 0) (type default) (color 0 0 0 0))
  )
  (wire (pts (xy 372.999 62.23) (xy 342.773 62.23))
    (stroke (width 0) (type default) (color 0 0 0 0))
  )
  (wire (pts (xy 224.79 67.945) (xy 244.475 67.945))
    (stroke (width 0) (type default) (color 0 0 0 0))
  )
  (wire (pts (xy 65.405 236.855) (xy 65.405 238.76))
    (stroke (width 0) (type default) (color 0 0 0 0))
  )
  (wire (pts (xy 115.57 68.58) (xy 97.79 68.58))
    (stroke (width 0) (type default) (color 0 0 0 0))
  )
  (wire (pts (xy 293.37 82.55) (xy 319.913 82.55))
    (stroke (width 0) (type default) (color 0 0 0 0))
  )
  (wire (pts (xy 149.86 76.2) (xy 157.48 76.2))
    (stroke (width 0) (type default) (color 0 0 0 0))
  )
  (wire (pts (xy 366.395 42.545) (xy 370.205 42.545))
    (stroke (width 0) (type default) (color 0 0 0 0))
  )
  (wire (pts (xy 266.065 147.955) (xy 266.065 152.4))
    (stroke (width 0) (type default) (color 0 0 0 0))
  )
  (wire (pts (xy 111.76 215.138) (xy 111.76 203.2))
    (stroke (width 0) (type default) (color 0 0 0 0))
  )
  (wire (pts (xy 115.57 254.127) (xy 115.57 254.635))
    (stroke (width 0) (type default) (color 0 0 0 0))
  )
  (wire (pts (xy 53.975 73.914) (xy 53.975 71.12))
    (stroke (width 0) (type default) (color 0 0 0 0))
  )
  (wire (pts (xy 266.065 146.05) (xy 276.225 146.05))
    (stroke (width 0) (type default) (color 0 0 0 0))
  )
  (wire (pts (xy 266.065 143.51) (xy 278.765 143.51))
    (stroke (width 0) (type default) (color 0 0 0 0))
  )
  (wire (pts (xy 107.95 63.5) (xy 116.332 63.5))
    (stroke (width 0) (type default) (color 0 0 0 0))
  )
  (wire (pts (xy 118.11 190.5) (xy 134.62 190.5))
    (stroke (width 0) (type default) (color 0 0 0 0))
  )
  (wire (pts (xy 280.035 220.345) (xy 320.548 220.345))
    (stroke (width 0) (type default) (color 0 0 0 0))
  )
  (wire (pts (xy 73.025 48.895) (xy 75.565 48.895))
    (stroke (width 0) (type default) (color 0 0 0 0))
  )
  (wire (pts (xy 184.15 260.35) (xy 201.295 260.35))
    (stroke (width 0) (type default) (color 0 0 0 0))
  )
  (wire (pts (xy 269.875 69.85) (xy 319.913 69.85))
    (stroke (width 0) (type default) (color 0 0 0 0))
  )
  (wire (pts (xy 343.408 210.185) (xy 371.348 210.185))
    (stroke (width 0) (type default) (color 0 0 0 0))
  )
  (wire (pts (xy 199.39 254) (xy 207.01 254))
    (stroke (width 0) (type default) (color 0 0 0 0))
  )
  (wire (pts (xy 64.77 215.9) (xy 73.66 215.9))
    (stroke (width 0) (type default) (color 0 0 0 0))
  )
  (wire (pts (xy 109.982 123.825) (xy 109.982 127.635))
    (stroke (width 0) (type default) (color 0 0 0 0))
  )
  (wire (pts (xy 177.165 76.2) (xy 184.785 76.2))
    (stroke (width 0) (type default) (color 0 0 0 0))
  )
  (wire (pts (xy 89.916 123.825) (xy 99.822 123.825))
    (stroke (width 0) (type default) (color 0 0 0 0))
  )
  (wire (pts (xy 232.41 266.7) (xy 246.38 266.7))
    (stroke (width 0) (type default) (color 0 0 0 0))
  )
  (wire (pts (xy 245.491 125.73) (xy 241.935 125.73))
    (stroke (width 0) (type default) (color 0 0 0 0))
  )
  (wire (pts (xy 66.675 236.855) (xy 65.405 236.855))
    (stroke (width 0) (type default) (color 0 0 0 0))
  )
  (wire (pts (xy 93.98 210.82) (xy 96.52 210.82))
    (stroke (width 0) (type default) (color 0 0 0 0))
  )
  (wire (pts (xy 347.345 233.045) (xy 347.345 243.205))
    (stroke (width 0) (type default) (color 0 0 0 0))
  )
  (wire (pts (xy 219.075 128.27) (xy 219.075 129.54))
    (stroke (width 0) (type default) (color 0 0 0 0))
  )
  (wire (pts (xy 151.765 244.475) (xy 151.765 245.745))
    (stroke (width 0) (type default) (color 0 0 0 0))
  )
  (wire (pts (xy 97.79 63.5) (xy 104.775 63.5))
    (stroke (width 0) (type default) (color 0 0 0 0))
  )
  (wire (pts (xy 277.495 258.445) (xy 277.495 257.175))
    (stroke (width 0) (type default) (color 0 0 0 0))
  )
  (wire (pts (xy 210.185 77.47) (xy 210.185 76.2))
    (stroke (width 0) (type default) (color 0 0 0 0))
  )
  (wire (pts (xy 189.865 70.485) (xy 189.865 77.47))
    (stroke (width 0) (type default) (color 0 0 0 0))
  )
  (wire (pts (xy 46.99 196.85) (xy 46.99 199.39))
    (stroke (width 0) (type default) (color 0 0 0 0))
  )
  (wire (pts (xy 229.235 76.2) (xy 236.855 76.2))
    (stroke (width 0) (type default) (color 0 0 0 0))
  )
  (wire (pts (xy 89.916 126.365) (xy 93.472 126.365))
    (stroke (width 0) (type default) (color 0 0 0 0))
  )
  (wire (pts (xy 120.777 123.825) (xy 109.982 123.825))
    (stroke (width 0) (type default) (color 0 0 0 0))
  )
  (wire (pts (xy 187.325 73.025) (xy 187.325 77.47))
    (stroke (width 0) (type default) (color 0 0 0 0))
  )
  (wire (pts (xy 89.916 156.845) (xy 91.44 156.845))
    (stroke (width 0) (type default) (color 0 0 0 0))
  )
  (wire (pts (xy 288.29 82.55) (xy 275.59 82.55))
    (stroke (width 0) (type default) (color 0 0 0 0))
  )
  (wire (pts (xy 26.67 199.39) (xy 36.83 199.39))
    (stroke (width 0) (type default) (color 0 0 0 0))
  )
  (wire (pts (xy 64.77 215.9) (xy 64.77 217.17))
    (stroke (width 0) (type default) (color 0 0 0 0))
  )
  (wire (pts (xy 91.44 164.465) (xy 91.44 161.925))
    (stroke (width 0) (type default) (color 0 0 0 0))
  )
  (wire (pts (xy 271.145 77.47) (xy 319.913 77.47))
    (stroke (width 0) (type default) (color 0 0 0 0))
  )
  (wire (pts (xy 99.187 75.057) (xy 99.187 73.66))
    (stroke (width 0) (type default) (color 0 0 0 0))
  )
  (wire (pts (xy 93.472 126.365) (xy 125.984 126.365))
    (stroke (width 0) (type default) (color 0 0 0 0))
  )
  (wire (pts (xy 343.408 233.045) (xy 347.345 233.045))
    (stroke (width 0) (type default) (color 0 0 0 0))
  )
  (wire (pts (xy 92.075 259.715) (xy 76.2 259.715))
    (stroke (width 0) (type default) (color 0 0 0 0))
  )
  (wire (pts (xy 378.079 82.55) (xy 387.35 82.55))
    (stroke (width 0) (type default) (color 0 0 0 0))
  )
  (wire (pts (xy 149.86 71.12) (xy 165.1 71.12))
    (stroke (width 0) (type default) (color 0 0 0 0))
  )
  (wire (pts (xy 193.04 237.49) (xy 207.01 237.49))
    (stroke (width 0) (type default) (color 0 0 0 0))
  )
  (wire (pts (xy 109.982 123.825) (xy 99.822 123.825))
    (stroke (width 0) (type default) (color 0 0 0 0))
  )
  (wire (pts (xy 183.515 73.025) (xy 187.325 73.025))
    (stroke (width 0) (type default) (color 0 0 0 0))
  )
  (wire (pts (xy 44.577 126.365) (xy 44.577 125.222))
    (stroke (width 0) (type default) (color 0 0 0 0))
  )
  (wire (pts (xy 343.408 227.965) (xy 373.761 227.965))
    (stroke (width 0) (type default) (color 0 0 0 0))
  )
  (wire (pts (xy 73.66 205.74) (xy 64.77 205.74))
    (stroke (width 0) (type default) (color 0 0 0 0))
  )
  (wire (pts (xy 111.76 62.865) (xy 111.76 66.04))
    (stroke (width 0) (type default) (color 0 0 0 0))
  )
  (wire (pts (xy 232.41 259.08) (xy 246.38 259.08))
    (stroke (width 0) (type default) (color 0 0 0 0))
  )
  (wire (pts (xy 74.93 68.58) (xy 74.93 71.12))
    (stroke (width 0) (type default) (color 0 0 0 0))
  )
  (wire (pts (xy 106.68 49.022) (xy 104.775 49.022))
    (stroke (width 0) (type default) (color 0 0 0 0))
  )
  (wire (pts (xy 97.028 141.986) (xy 113.538 141.986))
    (stroke (width 0) (type default) (color 0 0 0 0))
  )
  (wire (pts (xy 244.475 77.47) (xy 244.475 67.945))
    (stroke (width 0) (type default) (color 0 0 0 0))
  )
  (wire (pts (xy 313.69 80.01) (xy 313.69 67.31))
    (stroke (width 0) (type default) (color 0 0 0 0))
  )
  (wire (pts (xy 264.795 207.645) (xy 286.766 207.645))
    (stroke (width 0) (type default) (color 0 0 0 0))
  )
  (wire (pts (xy 151.765 236.855) (xy 159.893 236.855))
    (stroke (width 0) (type default) (color 0 0 0 0))
  )
  (wire (pts (xy 102.743 119.38) (xy 99.822 119.38))
    (stroke (width 0) (type default) (color 0 0 0 0))
  )
  (wire (pts (xy 89.916 161.925) (xy 91.44 161.925))
    (stroke (width 0) (type default) (color 0 0 0 0))
  )
  (wire (pts (xy 269.875 72.39) (xy 319.913 72.39))
    (stroke (width 0) (type default) (color 0 0 0 0))
  )
  (wire (pts (xy 375.539 85.09) (xy 387.35 85.09))
    (stroke (width 0) (type default) (color 0 0 0 0))
  )
  (wire (pts (xy 370.205 50.165) (xy 370.205 48.895))
    (stroke (width 0) (type default) (color 0 0 0 0))
  )
  (wire (pts (xy 97.028 141.986) (xy 97.028 133.985))
    (stroke (width 0) (type default) (color 0 0 0 0))
  )
  (wire (pts (xy 125.984 127.381) (xy 125.984 126.365))
    (stroke (width 0) (type default) (color 0 0 0 0))
  )
  (wire (pts (xy 204.597 76.2) (xy 204.597 80.645))
    (stroke (width 0) (type default) (color 0 0 0 0))
  )
  (wire (pts (xy 59.055 236.855) (xy 60.325 236.855))
    (stroke (width 0) (type default) (color 0 0 0 0))
  )
  (wire (pts (xy 224.79 70.485) (xy 241.935 70.485))
    (stroke (width 0) (type default) (color 0 0 0 0))
  )
  (wire (pts (xy 94.996 136.525) (xy 94.996 144.526))
    (stroke (width 0) (type default) (color 0 0 0 0))
  )
  (wire (pts (xy 342.773 80.01) (xy 349.25 80.01))
    (stroke (width 0) (type default) (color 0 0 0 0))
  )
  (wire (pts (xy 74.93 63.5) (xy 74.93 68.58))
    (stroke (width 0) (type default) (color 0 0 0 0))
  )
  (wire (pts (xy 104.775 63.5) (xy 107.95 63.5))
    (stroke (width 0) (type default) (color 0 0 0 0))
  )
  (wire (pts (xy 232.41 241.3) (xy 246.38 241.3))
    (stroke (width 0) (type default) (color 0 0 0 0))
  )
  (wire (pts (xy 380.365 50.165) (xy 370.205 50.165))
    (stroke (width 0) (type default) (color 0 0 0 0))
  )
  (wire (pts (xy 283.845 138.43) (xy 283.845 149.225))
    (stroke (width 0) (type default) (color 0 0 0 0))
  )
  (wire (pts (xy 115.443 249.555) (xy 125.222 249.555))
    (stroke (width 0) (type default) (color 0 0 0 0))
  )
  (wire (pts (xy 169.418 236.855) (xy 169.418 238.252))
    (stroke (width 0) (type default) (color 0 0 0 0))
  )
  (wire (pts (xy 26.67 190.5) (xy 36.83 190.5))
    (stroke (width 0) (type default) (color 0 0 0 0))
  )
  (wire (pts (xy 290.83 85.09) (xy 319.913 85.09))
    (stroke (width 0) (type default) (color 0 0 0 0))
  )
  (wire (pts (xy 378.841 227.965) (xy 400.05 227.965))
    (stroke (width 0) (type default) (color 0 0 0 0))
  )
  (wire (pts (xy 38.227 126.365) (xy 44.577 126.365))
    (stroke (width 0) (type default) (color 0 0 0 0))
  )
  (wire (pts (xy 275.209 64.77) (xy 286.639 64.77))
    (stroke (width 0) (type default) (color 0 0 0 0))
  )
  (wire (pts (xy 151.765 243.332) (xy 151.765 244.475))
    (stroke (width 0) (type default) (color 0 0 0 0))
  )
  (wire (pts (xy 151.765 244.475) (xy 159.893 244.475))
    (stroke (width 0) (type default) (color 0 0 0 0))
  )
  (wire (pts (xy 169.418 243.332) (xy 169.418 244.475))
    (stroke (width 0) (type default) (color 0 0 0 0))
  )
  (wire (pts (xy 99.187 73.66) (xy 97.79 73.66))
    (stroke (width 0) (type default) (color 0 0 0 0))
  )
  (wire (pts (xy 54.229 123.825) (xy 54.229 130.81))
    (stroke (width 0) (type default) (color 0 0 0 0))
  )
  (wire (pts (xy 112.395 254.635) (xy 115.57 254.635))
    (stroke (width 0) (type default) (color 0 0 0 0))
  )
  (wire (pts (xy 96.52 210.82) (xy 96.52 215.138))
    (stroke (width 0) (type default) (color 0 0 0 0))
  )
  (wire (pts (xy 319.913 80.01) (xy 313.69 80.01))
    (stroke (width 0) (type default) (color 0 0 0 0))
  )
  (wire (pts (xy 127.889 126.365) (xy 125.984 126.365))
    (stroke (width 0) (type default) (color 0 0 0 0))
  )
  (wire (pts (xy 349.885 212.725) (xy 349.885 196.215))
    (stroke (width 0) (type default) (color 0 0 0 0))
  )
  (wire (pts (xy 199.39 243.84) (xy 207.01 243.84))
    (stroke (width 0) (type default) (color 0 0 0 0))
  )
  (wire (pts (xy 291.846 207.645) (xy 320.548 207.645))
    (stroke (width 0) (type default) (color 0 0 0 0))
  )
  (wire (pts (xy 254.635 202.565) (xy 254.635 203.835))
    (stroke (width 0) (type default) (color 0 0 0 0))
  )
  (wire (pts (xy 370.459 85.09) (xy 342.773 85.09))
    (stroke (width 0) (type default) (color 0 0 0 0))
  )
  (wire (pts (xy 53.975 71.12) (xy 44.45 71.12))
    (stroke (width 0) (type default) (color 0 0 0 0))
  )
  (wire (pts (xy 232.41 261.62) (xy 246.38 261.62))
    (stroke (width 0) (type default) (color 0 0 0 0))
  )
  (wire (pts (xy 110.363 119.38) (xy 112.522 119.38))
    (stroke (width 0) (type default) (color 0 0 0 0))
  )
  (wire (pts (xy 165.1 77.47) (xy 165.1 71.12))
    (stroke (width 0) (type default) (color 0 0 0 0))
  )
  (wire (pts (xy 111.76 223.52) (xy 121.92 223.52))
    (stroke (width 0) (type default) (color 0 0 0 0))
  )
  (wire (pts (xy 212.725 125.73) (xy 210.82 125.73))
    (stroke (width 0) (type default) (color 0 0 0 0))
  )
  (wire (pts (xy 232.41 269.24) (xy 246.38 269.24))
    (stroke (width 0) (type default) (color 0 0 0 0))
  )
  (wire (pts (xy 89.662 271.145) (xy 89.662 269.875))
    (stroke (width 0) (type default) (color 0 0 0 0))
  )
  (wire (pts (xy 53.975 66.04) (xy 78.105 66.04))
    (stroke (width 0) (type default) (color 0 0 0 0))
  )
  (wire (pts (xy 91.44 156.845) (xy 91.44 159.385))
    (stroke (width 0) (type default) (color 0 0 0 0))
  )
  (wire (pts (xy 343.408 205.105) (xy 347.345 205.105))
    (stroke (width 0) (type default) (color 0 0 0 0))
  )
  (wire (pts (xy 194.945 77.47) (xy 194.945 65.405))
    (stroke (width 0) (type default) (color 0 0 0 0))
  )
  (wire (pts (xy 343.408 222.885) (xy 384.175 222.885))
    (stroke (width 0) (type default) (color 0 0 0 0))
  )
  (wire (pts (xy 275.209 62.23) (xy 289.179 62.23))
    (stroke (width 0) (type default) (color 0 0 0 0))
  )
  (wire (pts (xy 259.08 78.74) (xy 271.145 78.74))
    (stroke (width 0) (type default) (color 0 0 0 0))
  )
  (wire (pts (xy 306.07 138.43) (xy 321.183 138.43))
    (stroke (width 0) (type default) (color 0 0 0 0))
  )
  (wire (pts (xy 244.475 203.835) (xy 244.475 202.565))
    (stroke (width 0) (type default) (color 0 0 0 0))
  )
  (wire (pts (xy 278.765 143.51) (xy 278.765 149.225))
    (stroke (width 0) (type default) (color 0 0 0 0))
  )
  (wire (pts (xy 254.635 196.215) (xy 254.635 197.485))
    (stroke (width 0) (type default) (color 0 0 0 0))
  )
  (wire (pts (xy 236.855 77.47) (xy 236.855 76.2))
    (stroke (width 0) (type default) (color 0 0 0 0))
  )
  (wire (pts (xy 342.773 59.69) (xy 346.71 59.69))
    (stroke (width 0) (type default) (color 0 0 0 0))
  )
  (wire (pts (xy 197.485 70.485) (xy 215.265 70.485))
    (stroke (width 0) (type default) (color 0 0 0 0))
  )
  (wire (pts (xy 269.875 257.175) (xy 269.875 261.62))
    (stroke (width 0) (type default) (color 0 0 0 0))
  )
  (wire (pts (xy 319.913 67.31) (xy 313.69 67.31))
    (stroke (width 0) (type default) (color 0 0 0 0))
  )
  (wire (pts (xy 80.01 71.12) (xy 78.105 71.12))
    (stroke (width 0) (type default) (color 0 0 0 0))
  )
  (wire (pts (xy 97.79 66.04) (xy 111.76 66.04))
    (stroke (width 0) (type default) (color 0 0 0 0))
  )
  (wire (pts (xy 100.457 60.96) (xy 100.457 48.895))
    (stroke (width 0) (type default) (color 0 0 0 0))
  )
  (wire (pts (xy 36.83 199.39) (xy 46.99 199.39))
    (stroke (width 0) (type default) (color 0 0 0 0))
  )
  (wire (pts (xy 96.52 223.52) (xy 104.14 223.52))
    (stroke (width 0) (type default) (color 0 0 0 0))
  )
  (wire (pts (xy 149.86 73.66) (xy 162.56 73.66))
    (stroke (width 0) (type default) (color 0 0 0 0))
  )
  (wire (pts (xy 97.028 133.985) (xy 89.916 133.985))
    (stroke (width 0) (type default) (color 0 0 0 0))
  )
  (wire (pts (xy 370.459 64.77) (xy 342.773 64.77))
    (stroke (width 0) (type default) (color 0 0 0 0))
  )
  (wire (pts (xy 349.25 67.31) (xy 349.25 50.8))
    (stroke (width 0) (type default) (color 0 0 0 0))
  )
  (wire (pts (xy 287.655 251.46) (xy 287.655 258.445))
    (stroke (width 0) (type default) (color 0 0 0 0))
  )
  (wire (pts (xy 205.74 265.43) (xy 207.01 265.43))
    (stroke (width 0) (type default) (color 0 0 0 0))
  )
  (wire (pts (xy 104.14 223.52) (xy 111.76 223.52))
    (stroke (width 0) (type default) (color 0 0 0 0))
  )
  (wire (pts (xy 342.773 77.47) (xy 394.335 77.47))
    (stroke (width 0) (type default) (color 0 0 0 0))
  )
  (wire (pts (xy 229.235 76.2) (xy 229.235 80.645))
    (stroke (width 0) (type default) (color 0 0 0 0))
  )
  (wire (pts (xy 104.14 207.01) (xy 134.62 207.01))
    (stroke (width 0) (type default) (color 0 0 0 0))
  )
  (wire (pts (xy 115.697 259.08) (xy 115.697 259.715))
    (stroke (width 0) (type default) (color 0 0 0 0))
  )
  (wire (pts (xy 380.365 42.545) (xy 380.365 43.815))
    (stroke (width 0) (type default) (color 0 0 0 0))
  )
  (wire (pts (xy 349.25 50.8) (xy 350.52 50.8))
    (stroke (width 0) (type default) (color 0 0 0 0))
  )
  (wire (pts (xy 150.495 236.855) (xy 151.765 236.855))
    (stroke (width 0) (type default) (color 0 0 0 0))
  )

  (text "Debug" (at 14.605 113.665 0)
    (effects (font (size 2.0066 2.0066) (thickness 0.4013) bold) (justify left bottom))
  )
  (text "USB-C OTG/DP" (at 14.605 39.37 0)
    (effects (font (size 2.0066 2.0066) (thickness 0.4013) bold) (justify left bottom))
  )
  (text "USB-C  Host" (at 13.97 182.88 0)
    (effects (font (size 2.0066 2.0066) (thickness 0.4013) bold) (justify left bottom))
  )
  (text "Note:\nSBU ending with N/P \nto enable routing with \ndifferential tools"
    (at 102.616 82.677 0)
    (effects (font (size 1.27 1.27)) (justify left bottom))
  )
  (text "USB-C interfaces" (at 13.97 18.415 0)
    (effects (font (size 2.9972 2.9972) (thickness 0.5994) bold) (justify left bottom))
  )

  (label "USB2C_TX1_P" (at 246.38 246.38 180)
    (effects (font (size 1.27 1.27)) (justify right bottom))
  )
  (label "USB2C_RX2_P" (at 246.38 259.08 180)
    (effects (font (size 1.27 1.27)) (justify right bottom))
  )
  (label "DBG_USB_D_P" (at 306.07 143.51 0)
    (effects (font (size 1.27 1.27)) (justify left bottom))
  )
  (label "USB2_5V" (at 134.62 190.5 180)
    (effects (font (size 1.27 1.27)) (justify right bottom))
  )
  (label "USB2_CC1" (at 264.795 215.265 0)
    (effects (font (size 1.27 1.27)) (justify left bottom))
  )
  (label "USB2C_TX1_N" (at 264.795 210.185 0)
    (effects (font (size 1.27 1.27)) (justify left bottom))
  )
  (label "USB1C_TX0_C_P" (at 197.485 70.485 0)
    (effects (font (size 1.27 1.27)) (justify left bottom))
  )
  (label "USB2C_RX2_N" (at 264.795 227.965 0)
    (effects (font (size 1.27 1.27)) (justify left bottom))
  )
  (label "USB2_5V" (at 264.795 196.215 0)
    (effects (font (size 1.27 1.27)) (justify left bottom))
  )
  (label "DBG_USB_D_P" (at 128.778 141.986 180)
    (effects (font (size 1.27 1.27)) (justify right bottom))
  )
  (label "USB2_EN_5V" (at 76.2 259.715 0)
    (effects (font (size 1.27 1.27)) (justify left bottom))
  )
  (label "USB2C_RX1_C_P" (at 366.395 207.645 180)
    (effects (font (size 1.27 1.27)) (justify right bottom))
  )
  (label "USB2C_TX1_P" (at 264.795 207.645 0)
    (effects (font (size 1.27 1.27)) (justify left bottom))
  )
  (label "USB1C_RX1_C_N" (at 224.79 65.405 0)
    (effects (font (size 1.27 1.27)) (justify left bottom))
  )
  (label "USB2C_TX2_C_P" (at 366.395 230.505 180)
    (effects (font (size 1.27 1.27)) (justify right bottom))
  )
  (label "DBG_VBUS" (at 266.065 146.05 0)
    (effects (font (size 1.27 1.27)) (justify left bottom))
  )
  (label "USB1_SBU_P" (at 115.57 71.12 180)
    (effects (font (size 1.27 1.27)) (justify right bottom))
  )
  (label "USB2_FAULT_5V" (at 134.62 203.2 180)
    (effects (font (size 1.27 1.27)) (justify right bottom))
  )
  (label "USB2_FAULT_5V" (at 76.2 254.635 0)
    (effects (font (size 1.27 1.27)) (justify left bottom))
  )
  (label "USB1_SBU_N" (at 259.08 78.74 0)
    (effects (font (size 1.27 1.27)) (justify left bottom))
  )
  (label "USB2C_TX2_C_N" (at 366.395 227.965 180)
    (effects (font (size 1.27 1.27)) (justify right bottom))
  )
  (label "USB1C_RX0_C_N" (at 365.76 64.77 180)
    (effects (font (size 1.27 1.27)) (justify right bottom))
  )
  (label "USB2C_RX2_N" (at 246.38 261.62 180)
    (effects (font (size 1.27 1.27)) (justify right bottom))
  )
  (label "USB2_CC_SELECT" (at 134.62 210.82 180)
    (effects (font (size 1.27 1.27)) (justify right bottom))
  )
  (label "5V0_DBG" (at 260.985 125.73 180)
    (effects (font (size 1.27 1.27)) (justify right bottom))
  )
  (label "USB1C_RX1_C_P" (at 224.79 67.945 0)
    (effects (font (size 1.27 1.27)) (justify left bottom))
  )
  (label "USB2C_TX2_N" (at 246.38 269.24 180)
    (effects (font (size 1.27 1.27)) (justify right bottom))
  )
  (label "DBG_VBUS" (at 266.065 143.51 0)
    (effects (font (size 1.27 1.27)) (justify left bottom))
  )
  (label "USB1C_TX0_C_P" (at 297.18 62.23 0)
    (effects (font (size 1.27 1.27)) (justify left bottom))
  )
  (label "USB1C_RX0_C_P" (at 365.76 62.23 180)
    (effects (font (size 1.27 1.27)) (justify right bottom))
  )
  (label "USB2C_RX1_N" (at 400.05 210.185 180)
    (effects (font (size 1.27 1.27)) (justify right bottom))
  )
  (label "USB2_CC1" (at 107.95 195.58 180)
    (effects (font (size 1.27 1.27)) (justify right bottom))
  )
  (label "USB2C_RX1_N" (at 246.38 241.3 180)
    (effects (font (size 1.27 1.27)) (justify right bottom))
  )
  (label "USB2C_TX2_P" (at 400.05 230.505 180)
    (effects (font (size 1.27 1.27)) (justify right bottom))
  )
  (label "USB2_EN_5V" (at 56.515 195.58 0)
    (effects (font (size 1.27 1.27)) (justify left bottom))
  )
  (label "USB2C_RX2_C_N" (at 297.815 227.965 0)
    (effects (font (size 1.27 1.27)) (justify left bottom))
  )
  (label "USB1C_RX0_C_N" (at 197.485 67.945 0)
    (effects (font (size 1.27 1.27)) (justify left bottom))
  )
  (label "DBG_VBUS" (at 359.41 151.13 180)
    (effects (font (size 1.27 1.27)) (justify right bottom))
  )
  (label "USB1_SBU_N" (at 149.86 73.66 0)
    (effects (font (size 1.27 1.27)) (justify left bottom))
  )
  (label "DBG_VBUS" (at 306.07 138.43 0)
    (effects (font (size 1.27 1.27)) (justify left bottom))
  )
  (label "USB1C_RX0_C_P" (at 197.485 65.405 0)
    (effects (font (size 1.27 1.27)) (justify left bottom))
  )
  (label "USB2C_RX2_C_P" (at 297.815 230.505 0)
    (effects (font (size 1.27 1.27)) (justify left bottom))
  )
  (label "USB2C_TX1_N" (at 246.38 248.92 180)
    (effects (font (size 1.27 1.27)) (justify right bottom))
  )
  (label "DBG_USB_D_N" (at 266.065 138.43 0)
    (effects (font (size 1.27 1.27)) (justify left bottom))
  )
  (label "USB1C_TX0_C_N" (at 297.18 64.77 0)
    (effects (font (size 1.27 1.27)) (justify left bottom))
  )
  (label "USB2C_RX1_C_N" (at 366.395 210.185 180)
    (effects (font (size 1.27 1.27)) (justify right bottom))
  )
  (label "USB2_5V" (at 234.315 196.215 0)
    (effects (font (size 1.27 1.27)) (justify left bottom))
  )
  (label "USB1C_TX1_C_N" (at 365.76 82.55 180)
    (effects (font (size 1.27 1.27)) (justify right bottom))
  )
  (label "USB1C_TX1_C_N" (at 224.79 70.485 0)
    (effects (font (size 1.27 1.27)) (justify left bottom))
  )
  (label "USB1C_RX1_C_P" (at 297.18 85.09 0)
    (effects (font (size 1.27 1.27)) (justify left bottom))
  )
  (label "USB2_CC2" (at 400.05 223.52 180)
    (effects (font (size 1.27 1.27)) (justify right bottom))
  )
  (label "USB2C_TX1_C_N" (at 297.815 210.185 0)
    (effects (font (size 1.27 1.27)) (justify left bottom))
  )
  (label "USB2_CC2" (at 107.95 198.12 180)
    (effects (font (size 1.27 1.27)) (justify right bottom))
  )
  (label "USB1_SBU_P" (at 149.86 71.12 0)
    (effects (font (size 1.27 1.27)) (justify left bottom))
  )
  (label "USB2_CC_SELECT" (at 184.15 260.35 0)
    (effects (font (size 1.27 1.27)) (justify left bottom))
  )
  (label "USB_SBU_NP_N" (at 69.85 71.12 180)
    (effects (font (size 1.27 1.27)) (justify right bottom))
  )
  (label "USB2_SINK_5V" (at 76.2 249.555 0)
    (effects (font (size 1.27 1.27)) (justify left bottom))
  )
  (label "USB2C_RX1_P" (at 400.05 207.645 180)
    (effects (font (size 1.27 1.27)) (justify right bottom))
  )
  (label "USB1C_TX1_C_P" (at 365.76 85.09 180)
    (effects (font (size 1.27 1.27)) (justify right bottom))
  )
  (label "USB1_SBU_N" (at 115.57 68.58 180)
    (effects (font (size 1.27 1.27)) (justify right bottom))
  )
  (label "DBG_VBUS" (at 295.275 125.73 180)
    (effects (font (size 1.27 1.27)) (justify right bottom))
  )
  (label "DBG_USB_D_N" (at 359.41 143.51 180)
    (effects (font (size 1.27 1.27)) (justify right bottom))
  )
  (label "USB1C_RX1_C_N" (at 297.307 82.55 0)
    (effects (font (size 1.27 1.27)) (justify left bottom))
  )
  (label "5V0_DBG" (at 120.777 123.825 180)
    (effects (font (size 1.27 1.27)) (justify right bottom))
  )
  (label "DBG_USB_D_N" (at 306.07 146.05 0)
    (effects (font (size 1.27 1.27)) (justify left bottom))
  )
  (label "DBG_VBUS" (at 306.07 151.13 0)
    (effects (font (size 1.27 1.27)) (justify left bottom))
  )
  (label "USB2C_TX2_P" (at 246.38 266.7 180)
    (effects (font (size 1.27 1.27)) (justify right bottom))
  )
  (label "DBG_USB_D_P" (at 266.065 140.97 0)
    (effects (font (size 1.27 1.27)) (justify left bottom))
  )
  (label "USB2C_RX1_P" (at 246.38 238.76 180)
    (effects (font (size 1.27 1.27)) (justify right bottom))
  )
  (label "USB1_SBU_P" (at 403.86 69.85 180)
    (effects (font (size 1.27 1.27)) (justify right bottom))
  )
  (label "DBG_VBUS" (at 359.41 138.43 180)
    (effects (font (size 1.27 1.27)) (justify right bottom))
  )
  (label "USB1C_TX1_C_P" (at 224.79 73.025 0)
    (effects (font (size 1.27 1.27)) (justify left bottom))
  )
  (label "DBG_USB_D_P" (at 359.41 146.05 180)
    (effects (font (size 1.27 1.27)) (justify right bottom))
  )
  (label "USB2C_TX2_N" (at 400.05 227.965 180)
    (effects (font (size 1.27 1.27)) (justify right bottom))
  )
  (label "USB2C_TX1_C_P" (at 297.815 207.645 0)
    (effects (font (size 1.27 1.27)) (justify left bottom))
  )
  (label "DBG_USB_D_N" (at 128.778 144.526 180)
    (effects (font (size 1.27 1.27)) (justify right bottom))
  )
  (label "USB_SBU_NP_P" (at 69.85 66.04 180)
    (effects (font (size 1.27 1.27)) (justify right bottom))
  )
  (label "USB1C_TX0_C_N" (at 197.485 73.025 0)
    (effects (font (size 1.27 1.27)) (justify left bottom))
  )
  (label "USB2_SINK_5V" (at 134.62 207.01 180)
    (effects (font (size 1.27 1.27)) (justify right bottom))
  )
  (label "USB2C_RX2_P" (at 264.795 230.505 0)
    (effects (font (size 1.27 1.27)) (justify left bottom))
  )

  (global_label "EDP_AUX_N" (shape input) (at 31.75 71.12 180) (fields_autoplaced)
    (effects (font (size 1.27 1.27)) (justify right))
    (property "Intersheet References" "${INTERSHEET_REFS}" (id 0) (at 0 0 0)
      (effects (font (size 1.27 1.27)) hide)
    )
  )
  (global_label "USB_VBUS" (shape input) (at 366.395 42.545 180) (fields_autoplaced)
    (effects (font (size 1.27 1.27)) (justify right))
    (property "Intersheet References" "${INTERSHEET_REFS}" (id 0) (at 0 0 0)
      (effects (font (size 1.27 1.27)) hide)
    )
  )
  (global_label "3V3_SYS" (shape input) (at 52.705 55.88 180) (fields_autoplaced)
    (effects (font (size 1.27 1.27)) (justify right))
    (property "Intersheet References" "${INTERSHEET_REFS}" (id 0) (at 0 0 0)
      (effects (font (size 1.27 1.27)) hide)
    )
  )
  (global_label "USB1_SS_RX1_P" (shape input) (at 275.59 85.09 180) (fields_autoplaced)
    (effects (font (size 1.27 1.27)) (justify right))
    (property "Intersheet References" "${INTERSHEET_REFS}" (id 0) (at 0 0 0)
      (effects (font (size 1.27 1.27)) hide)
    )
  )
  (global_label "USB2C_HS_D_N" (shape bidirectional) (at 384.81 217.805 0) (fields_autoplaced)
    (effects (font (size 1.27 1.27)) (justify left))
    (property "Intersheet References" "${INTERSHEET_REFS}" (id 0) (at 0 0 0)
      (effects (font (size 1.27 1.27)) hide)
    )
  )
  (global_label "3V3_SYS" (shape input) (at 193.04 237.49 180) (fields_autoplaced)
    (effects (font (size 1.27 1.27)) (justify right))
    (property "Intersheet References" "${INTERSHEET_REFS}" (id 0) (at 0 0 0)
      (effects (font (size 1.27 1.27)) hide)
    )
  )
  (global_label "5V_SYS" (shape input) (at 66.675 236.855 0) (fields_autoplaced)
    (effects (font (size 1.27 1.27)) (justify left))
    (property "Intersheet References" "${INTERSHEET_REFS}" (id 0) (at 0 0 0)
      (effects (font (size 1.27 1.27)) hide)
    )
  )
  (global_label "USB1_SS_RX0_N" (shape input) (at 387.35 64.77 0) (fields_autoplaced)
    (effects (font (size 1.27 1.27)) (justify left))
    (property "Intersheet References" "${INTERSHEET_REFS}" (id 0) (at 0 0 0)
      (effects (font (size 1.27 1.27)) hide)
    )
  )
  (global_label "USB2C_HS_D_P" (shape bidirectional) (at 277.495 254 180) (fields_autoplaced)
    (effects (font (size 1.27 1.27)) (justify right))
    (property "Intersheet References" "${INTERSHEET_REFS}" (id 0) (at 0 0 0)
      (effects (font (size 1.27 1.27)) hide)
    )
  )
  (global_label "VREG_S4A_1V8" (shape input) (at 106.68 49.022 0) (fields_autoplaced)
    (effects (font (size 1.27 1.27)) (justify left))
    (property "Intersheet References" "${INTERSHEET_REFS}" (id 0) (at 0 -4.318 0)
      (effects (font (size 1.27 1.27)) hide)
    )
  )
  (global_label "USB1_D_N" (shape bidirectional) (at 269.875 74.93 180) (fields_autoplaced)
    (effects (font (size 1.27 1.27)) (justify right))
    (property "Intersheet References" "${INTERSHEET_REFS}" (id 0) (at 0 0 0)
      (effects (font (size 1.27 1.27)) hide)
    )
  )
  (global_label "1V8_SYS" (shape input) (at 117.475 236.855 0) (fields_autoplaced)
    (effects (font (size 1.27 1.27)) (justify left))
    (property "Intersheet References" "${INTERSHEET_REFS}" (id 0) (at 0 0 0)
      (effects (font (size 1.27 1.27)) hide)
    )
  )
  (global_label "5V_SYS" (shape input) (at 121.92 223.52 0) (fields_autoplaced)
    (effects (font (size 1.27 1.27)) (justify left))
    (property "Intersheet References" "${INTERSHEET_REFS}" (id 0) (at 0 0 0)
      (effects (font (size 1.27 1.27)) hide)
    )
  )
  (global_label "SBU_SW_OE" (shape input) (at 116.332 63.5 0) (fields_autoplaced)
    (effects (font (size 1.27 1.27)) (justify left))
    (property "Intersheet References" "${INTERSHEET_REFS}" (id 0) (at 3.302 0 0)
      (effects (font (size 1.27 1.27)) hide)
    )
  )
  (global_label "USB1_SS_TX0_N" (shape output) (at 275.209 64.77 180) (fields_autoplaced)
    (effects (font (size 1.27 1.27)) (justify right))
    (property "Intersheet References" "${INTERSHEET_REFS}" (id 0) (at -0.381 0 0)
      (effects (font (size 1.27 1.27)) hide)
    )
  )
  (global_label "USB2C_HS_D_P" (shape bidirectional) (at 384.81 220.345 0) (fields_autoplaced)
    (effects (font (size 1.27 1.27)) (justify left))
    (property "Intersheet References" "${INTERSHEET_REFS}" (id 0) (at 0 0 0)
      (effects (font (size 1.27 1.27)) hide)
    )
  )
  (global_label "3V3_SYS" (shape input) (at 73.025 48.895 180) (fields_autoplaced)
    (effects (font (size 1.27 1.27)) (justify right))
    (property "Intersheet References" "${INTERSHEET_REFS}" (id 0) (at 0 0 0)
      (effects (font (size 1.27 1.27)) hide)
    )
  )
  (global_label "USB_CC1" (shape bidirectional) (at 269.875 69.85 180) (fields_autoplaced)
    (effects (font (size 1.27 1.27)) (justify right))
    (property "Intersheet References" "${INTERSHEET_REFS}" (id 0) (at 0 0 0)
      (effects (font (size 1.27 1.27)) hide)
    )
  )
  (global_label "DBG_TXD" (shape input) (at 38.227 128.905 180) (fields_autoplaced)
    (effects (font (size 1.27 1.27)) (justify right))
    (property "Intersheet References" "${INTERSHEET_REFS}" (id 0) (at -13.208 284.48 0)
      (effects (font (size 1.27 1.27)) hide)
    )
  )
  (global_label "USB2_EN" (shape input) (at 125.222 259.715 0) (fields_autoplaced)
    (effects (font (size 1.27 1.27)) (justify left))
    (property "Intersheet References" "${INTERSHEET_REFS}" (id 0) (at 3.302 0 0)
      (effects (font (size 1.27 1.27)) hide)
    )
  )
  (global_label "USB1_SS_RX0_P" (shape input) (at 387.35 62.23 0) (fields_autoplaced)
    (effects (font (size 1.27 1.27)) (justify left))
    (property "Intersheet References" "${INTERSHEET_REFS}" (id 0) (at 0 0 0)
      (effects (font (size 1.27 1.27)) hide)
    )
  )
  (global_label "USB2_SINK" (shape output) (at 125.222 249.555 0) (fields_autoplaced)
    (effects (font (size 1.27 1.27)) (justify left))
    (property "Intersheet References" "${INTERSHEET_REFS}" (id 0) (at 3.302 0 0)
      (effects (font (size 1.27 1.27)) hide)
    )
  )
  (global_label "EDP_AUX_P" (shape input) (at 31.75 66.04 180) (fields_autoplaced)
    (effects (font (size 1.27 1.27)) (justify right))
    (property "Intersheet References" "${INTERSHEET_REFS}" (id 0) (at 0 0 0)
      (effects (font (size 1.27 1.27)) hide)
    )
  )
  (global_label "USB_CC2" (shape bidirectional) (at 394.335 77.47 0) (fields_autoplaced)
    (effects (font (size 1.27 1.27)) (justify left))
    (property "Intersheet References" "${INTERSHEET_REFS}" (id 0) (at 0 0 0)
      (effects (font (size 1.27 1.27)) hide)
    )
  )
  (global_label "USB1_SS_RX1_N" (shape input) (at 275.59 82.55 180) (fields_autoplaced)
    (effects (font (size 1.27 1.27)) (justify right))
    (property "Intersheet References" "${INTERSHEET_REFS}" (id 0) (at 0 0 0)
      (effects (font (size 1.27 1.27)) hide)
    )
  )
  (global_label "USB_CC2" (shape bidirectional) (at 183.515 65.405 180) (fields_autoplaced)
    (effects (font (size 1.27 1.27)) (justify right))
    (property "Intersheet References" "${INTERSHEET_REFS}" (id 0) (at 0 0 0)
      (effects (font (size 1.27 1.27)) hide)
    )
  )
  (global_label "USB2C_HS_D_N" (shape bidirectional) (at 277.495 251.46 180) (fields_autoplaced)
    (effects (font (size 1.27 1.27)) (justify right))
    (property "Intersheet References" "${INTERSHEET_REFS}" (id 0) (at 0 0 0)
      (effects (font (size 1.27 1.27)) hide)
    )
  )
  (global_label "DBG_RXD" (shape output) (at 38.227 126.365 180) (fields_autoplaced)
    (effects (font (size 1.27 1.27)) (justify right))
    (property "Intersheet References" "${INTERSHEET_REFS}" (id 0) (at -13.208 284.48 0)
      (effects (font (size 1.27 1.27)) hide)
    )
  )
  (global_label "SBU_SW_SEL" (shape input) (at 116.332 66.04 0) (fields_autoplaced)
    (effects (font (size 1.27 1.27)) (justify left))
    (property "Intersheet References" "${INTERSHEET_REFS}" (id 0) (at 3.302 0 0)
      (effects (font (size 1.27 1.27)) hide)
    )
  )
  (global_label "5V_SYS" (shape input) (at 25.4 190.5 180) (fields_autoplaced)
    (effects (font (size 1.27 1.27)) (justify right))
    (property "Intersheet References" "${INTERSHEET_REFS}" (id 0) (at 0 0 0)
      (effects (font (size 1.27 1.27)) hide)
    )
  )
  (global_label "USB1_D_P" (shape bidirectional) (at 394.335 74.93 0) (fields_autoplaced)
    (effects (font (size 1.27 1.27)) (justify left))
    (property "Intersheet References" "${INTERSHEET_REFS}" (id 0) (at 0 0 0)
      (effects (font (size 1.27 1.27)) hide)
    )
  )
  (global_label "USB_VBUS" (shape bidirectional) (at 350.52 50.8 0) (fields_autoplaced)
    (effects (font (size 1.27 1.27)) (justify left))
    (property "Intersheet References" "${INTERSHEET_REFS}" (id 0) (at 0 0 0)
      (effects (font (size 1.27 1.27)) hide)
    )
  )
  (global_label "USB1_D_P" (shape bidirectional) (at 183.515 70.485 180) (fields_autoplaced)
    (effects (font (size 1.27 1.27)) (justify right))
    (property "Intersheet References" "${INTERSHEET_REFS}" (id 0) (at 0 0 0)
      (effects (font (size 1.27 1.27)) hide)
    )
  )
  (global_label "USB1_SS_TX1_N" (shape input) (at 387.35 82.55 0) (fields_autoplaced)
    (effects (font (size 1.27 1.27)) (justify left))
    (property "Intersheet References" "${INTERSHEET_REFS}" (id 0) (at 0 0 0)
      (effects (font (size 1.27 1.27)) hide)
    )
  )
  (global_label "USB2C_HS_D_N" (shape bidirectional) (at 280.035 220.345 180) (fields_autoplaced)
    (effects (font (size 1.27 1.27)) (justify right))
    (property "Intersheet References" "${INTERSHEET_REFS}" (id 0) (at 0 0 0)
      (effects (font (size 1.27 1.27)) hide)
    )
  )
  (global_label "5V_SYS" (shape input) (at 64.77 190.5 180) (fields_autoplaced)
    (effects (font (size 1.27 1.27)) (justify right))
    (property "Intersheet References" "${INTERSHEET_REFS}" (id 0) (at 0 0 0)
      (effects (font (size 1.27 1.27)) hide)
    )
  )
  (global_label "USB1_SS_TX0_P" (shape output) (at 275.209 62.23 180) (fields_autoplaced)
    (effects (font (size 1.27 1.27)) (justify right))
    (property "Intersheet References" "${INTERSHEET_REFS}" (id 0) (at -0.381 0 0)
      (effects (font (size 1.27 1.27)) hide)
    )
  )
  (global_label "USB2_SS_RX_N" (shape input) (at 199.39 246.38 180) (fields_autoplaced)
    (effects (font (size 1.27 1.27)) (justify right))
    (property "Intersheet References" "${INTERSHEET_REFS}" (id 0) (at 0 0 0)
      (effects (font (size 1.27 1.27)) hide)
    )
  )
  (global_label "USB2_FAULT" (shape output) (at 125.222 254.635 0) (fields_autoplaced)
    (effects (font (size 1.27 1.27)) (justify left))
    (property "Intersheet References" "${INTERSHEET_REFS}" (id 0) (at 3.302 0 0)
      (effects (font (size 1.27 1.27)) hide)
    )
  )
  (global_label "1V8_DBG" (shape output) (at 210.82 125.73 180) (fields_autoplaced)
    (effects (font (size 1.27 1.27)) (justify right))
    (property "Intersheet References" "${INTERSHEET_REFS}" (id 0) (at 0 0 0)
      (effects (font (size 1.27 1.27)) hide)
    )
  )
  (global_label "USB1_D_N" (shape bidirectional) (at 394.335 72.39 0) (fields_autoplaced)
    (effects (font (size 1.27 1.27)) (justify left))
    (property "Intersheet References" "${INTERSHEET_REFS}" (id 0) (at 0 0 0)
      (effects (font (size 1.27 1.27)) hide)
    )
  )
  (global_label "1V8_SYS" (shape input) (at 59.055 236.855 180) (fields_autoplaced)
    (effects (font (size 1.27 1.27)) (justify right))
    (property "Intersheet References" "${INTERSHEET_REFS}" (id 0) (at 0 0 0)
      (effects (font (size 1.27 1.27)) hide)
    )
  )
  (global_label "USB1_SS_TX1_P" (shape input) (at 387.35 85.09 0) (fields_autoplaced)
    (effects (font (size 1.27 1.27)) (justify left))
    (property "Intersheet References" "${INTERSHEET_REFS}" (id 0) (at 0 0 0)
      (effects (font (size 1.27 1.27)) hide)
    )
  )
  (global_label "5V_SYS" (shape input) (at 86.995 244.475 180) (fields_autoplaced)
    (effects (font (size 1.27 1.27)) (justify right))
    (property "Intersheet References" "${INTERSHEET_REFS}" (id 0) (at -7.62 7.62 0)
      (effects (font (size 1.27 1.27)) hide)
    )
  )
  (global_label "USB1_D_P" (shape bidirectional) (at 269.875 72.39 180) (fields_autoplaced)
    (effects (font (size 1.27 1.27)) (justify right))
    (property "Intersheet References" "${INTERSHEET_REFS}" (id 0) (at 0 0 0)
      (effects (font (size 1.27 1.27)) hide)
    )
  )
  (global_label "USB_CC1" (shape bidirectional) (at 183.515 73.025 180) (fields_autoplaced)
    (effects (font (size 1.27 1.27)) (justify right))
    (property "Intersheet References" "${INTERSHEET_REFS}" (id 0) (at 0 0 0)
      (effects (font (size 1.27 1.27)) hide)
    )
  )
  (global_label "USB1_D_N" (shape bidirectional) (at 183.515 67.945 180) (fields_autoplaced)
    (effects (font (size 1.27 1.27)) (justify right))
    (property "Intersheet References" "${INTERSHEET_REFS}" (id 0) (at 0 0 0)
      (effects (font (size 1.27 1.27)) hide)
    )
  )
  (global_label "3V3_SYS" (shape input) (at 150.495 236.855 180) (fields_autoplaced)
    (effects (font (size 1.27 1.27)) (justify right))
    (property "Intersheet References" "${INTERSHEET_REFS}" (id 0) (at 0 0 0)
      (effects (font (size 1.27 1.27)) hide)
    )
  )
  (global_label "USB2_SS_TX_N" (shape output) (at 199.39 254 180) (fields_autoplaced)
    (effects (font (size 1.27 1.27)) (justify right))
    (property "Intersheet References" "${INTERSHEET_REFS}" (id 0) (at 0 0 0)
      (effects (font (size 1.27 1.27)) hide)
    )
  )
  (global_label "USB2_SS_RX_P" (shape input) (at 199.39 243.84 180) (fields_autoplaced)
    (effects (font (size 1.27 1.27)) (justify right))
    (property "Intersheet References" "${INTERSHEET_REFS}" (id 0) (at 0 0 0)
      (effects (font (size 1.27 1.27)) hide)
    )
  )
  (global_label "USB2_SS_TX_P" (shape output) (at 199.39 251.46 180) (fields_autoplaced)
    (effects (font (size 1.27 1.27)) (justify right))
    (property "Intersheet References" "${INTERSHEET_REFS}" (id 0) (at 0 0 0)
      (effects (font (size 1.27 1.27)) hide)
    )
  )
  (global_label "USB2C_HS_D_P" (shape bidirectional) (at 280.035 217.805 180) (fields_autoplaced)
    (effects (font (size 1.27 1.27)) (justify right))
    (property "Intersheet References" "${INTERSHEET_REFS}" (id 0) (at 0 0 0)
      (effects (font (size 1.27 1.27)) hide)
    )
  )
  (global_label "1V8_DBG" (shape input) (at 127.889 126.365 0) (fields_autoplaced)
    (effects (font (size 1.27 1.27)) (justify left))
    (property "Intersheet References" "${INTERSHEET_REFS}" (id 0) (at 188.214 -1.27 0)
      (effects (font (size 1.27 1.27)) (justify left) hide)
    )
  )
  (global_label "5V_SYS" (shape input) (at 112.522 119.38 0) (fields_autoplaced)
    (effects (font (size 1.27 1.27)) (justify left))
    (property "Intersheet References" "${INTERSHEET_REFS}" (id 0) (at -1.778 -3.81 0)
      (effects (font (size 1.27 1.27)) hide)
    )
  )

  (symbol (lib_id "sa800u-baseboard-hw:GND") (at 99.187 75.057 0) (mirror y) (unit 1)
    (in_bom yes) (on_board yes) (fields_autoplaced)
    (property "Reference" "#PWR049" (id 0) (at 99.187 81.407 0)
      (effects (font (size 1.27 1.27)) hide)
    )
    (property "Value" "GND" (id 1) (at 99.187 80.137 0))
    (property "Footprint" "" (id 2) (at 99.187 75.057 0)
      (effects (font (size 1.27 1.27)) hide)
    )
    (property "Datasheet" "" (id 3) (at 99.187 75.057 0)
      (effects (font (size 1.27 1.27)) hide)
    )
    (property "Author" "Antmicro" (id 4) (at 90.297 82.677 0)
      (effects (font (size 1.27 1.27) (thickness 0.15)) (justify left bottom) hide)
    )
    (property "License" "Apache-2.0" (id 5) (at 90.297 85.217 0)
      (effects (font (size 1.27 1.27) (thickness 0.15)) (justify left bottom) hide)
    )
    (pin "1")
  )

  (symbol (lib_id "sa800u-baseboard-hw:GND") (at 75.565 55.245 0) (mirror y) (unit 1)
    (in_bom yes) (on_board yes) (fields_autoplaced)
    (property "Reference" "#PWR047" (id 0) (at 75.565 61.595 0)
      (effects (font (size 1.27 1.27)) hide)
    )
    (property "Value" "GND" (id 1) (at 73.66 56.5149 0)
      (effects (font (size 1.27 1.27)) (justify left))
    )
    (property "Footprint" "" (id 2) (at 75.565 55.245 0)
      (effects (font (size 1.27 1.27)) hide)
    )
    (property "Datasheet" "" (id 3) (at 75.565 55.245 0)
      (effects (font (size 1.27 1.27)) hide)
    )
    (property "Author" "Antmicro" (id 4) (at 66.675 62.865 0)
      (effects (font (size 1.27 1.27) (thickness 0.15)) (justify left bottom) hide)
    )
    (property "License" "Apache-2.0" (id 5) (at 66.675 65.405 0)
      (effects (font (size 1.27 1.27) (thickness 0.15)) (justify left bottom) hide)
    )
    (pin "1")
  )

  (symbol (lib_id "sa800u-baseboard-hw:C_1u_0402") (at 75.565 50.165 90) (mirror x) (unit 1)
    (in_bom yes) (on_board yes) (fields_autoplaced)
    (property "Reference" "C66" (id 0) (at 78.232 51.4413 90)
      (effects (font (size 1.524 1.524)) (justify right))
    )
    (property "Value" "C_1u_0402" (id 1) (at 79.375 50.165 0)
      (effects (font (size 1.524 1.524)) hide)
    )
    (property "Footprint" "sa800u-baseboard-hw-footprints:C_0402_1005Metric" (id 2) (at 70.485 55.245 0)
      (effects (font (size 1.524 1.524)) (justify left) hide)
    )
    (property "Datasheet" " " (id 3) (at 75.565 50.165 0)
      (effects (font (size 1.27 1.27)) hide)
    )
    (property "Manufacturer" "TDK" (id 4) (at 65.405 55.245 0)
      (effects (font (size 1.524 1.524)) (justify left) hide)
    )
    (property "MPN" "C1005X6S1A105K050BC" (id 5) (at 67.945 55.245 0)
      (effects (font (size 1.524 1.524)) (justify left) hide)
    )
    (property "Val" "1u" (id 6) (at 78.232 54.6162 90)
      (effects (font (size 1.27 1.27)) (justify right))
    )
    (property "License" "Apache-2.0" (id 7) (at 98.425 70.485 0)
      (effects (font (size 1.27 1.27) (thickness 0.15)) (justify left bottom) hide)
    )
    (property "Author" "Antmicro" (id 8) (at 100.965 70.485 0)
      (effects (font (size 1.27 1.27) (thickness 0.15)) (justify left bottom) hide)
    )
    (property "Voltage" "" (id 9) (at 103.505 70.485 0)
      (effects (font (size 1.27 1.27)) (justify left bottom) hide)
    )
    (property "Dielectric" "" (id 10) (at 106.045 70.485 0)
      (effects (font (size 1.27 1.27)) (justify left bottom) hide)
    )
    (pin "1")
    (pin "2")
  )

  (symbol (lib_id "sa800u-baseboard-hw:R_2k2_0402") (at 104.775 55.245 90) (unit 1)
    (in_bom yes) (on_board yes) (fields_autoplaced)
    (property "Reference" "R62" (id 0) (at 106.68 51.435 90)
      (effects (font (size 1.524 1.524)) (justify right))
    )
    (property "Value" "R_2k2_0402" (id 1) (at 108.585 55.245 0)
      (effects (font (size 1.524 1.524)) hide)
    )
    (property "Footprint" "sa800u-baseboard-hw-footprints:R_0402_1005Metric" (id 2) (at 99.695 50.165 0)
      (effects (font (size 1.524 1.524)) (justify left) hide)
    )
    (property "Datasheet" "https://www.bourns.com/docs/product-datasheets/cr.pdf" (id 3) (at 104.775 55.245 0)
      (effects (font (size 1.27 1.27)) hide)
    )
    (property "Manufacturer" "Bourns" (id 4) (at 94.615 50.165 0)
      (effects (font (size 1.524 1.524)) (justify left) hide)
    )
    (property "MPN" "CR0402-FX-2201GLF" (id 5) (at 97.155 50.165 0)
      (effects (font (size 1.524 1.524)) (justify left) hide)
    )
    (property "Val" "2k2" (id 6) (at 106.68 54.6099 90)
      (effects (font (size 1.27 1.27)) (justify right))
    )
    (property "License" "Apache-2.0" (id 7) (at 130.175 34.925 0)
      (effects (font (size 1.27 1.27) (thickness 0.15)) (justify left bottom) hide)
    )
    (property "Author" "Antmicro" (id 8) (at 132.715 34.925 0)
      (effects (font (size 1.27 1.27) (thickness 0.15)) (justify left bottom) hide)
    )
    (property "Tolerance" "1%" (id 9) (at 114.935 34.925 0)
      (effects (font (size 1.27 1.27)) (justify left bottom) hide)
    )
    (pin "1")
    (pin "2")
  )

  (symbol (lib_id "sa800u-baseboard-hw:R_100k_0402") (at 53.975 73.914 90) (mirror x) (unit 1)
    (in_bom yes) (on_board yes) (fields_autoplaced)
    (property "Reference" "R58" (id 0) (at 55.88 75.184 90)
      (effects (font (size 1.524 1.524)) (justify right))
    )
    (property "Value" "R_100k_0402" (id 1) (at 57.785 73.914 0)
      (effects (font (size 1.524 1.524)) hide)
    )
    (property "Footprint" "sa800u-baseboard-hw-footprints:R_0402_1005Metric" (id 2) (at 48.895 78.994 0)
      (effects (font (size 1.524 1.524)) (justify left) hide)
    )
    (property "Datasheet" "https://www.bourns.com/docs/product-datasheets/cr.pdf" (id 3) (at 53.975 73.914 0)
      (effects (font (size 1.27 1.27)) hide)
    )
    (property "Manufacturer" "Bourns" (id 4) (at 43.815 78.994 0)
      (effects (font (size 1.524 1.524)) (justify left) hide)
    )
    (property "MPN" "CR0402-FX-1003GLF" (id 5) (at 46.355 78.994 0)
      (effects (font (size 1.524 1.524)) (justify left) hide)
    )
    (property "Val" "100k" (id 6) (at 55.88 78.3589 90)
      (effects (font (size 1.27 1.27)) (justify right))
    )
    (property "License" "Apache-2.0" (id 7) (at 79.375 94.234 0)
      (effects (font (size 1.27 1.27) (thickness 0.15)) (justify left bottom) hide)
    )
    (property "Author" "Antmicro" (id 8) (at 81.915 94.234 0)
      (effects (font (size 1.27 1.27) (thickness 0.15)) (justify left bottom) hide)
    )
    (property "Tolerance" "1%" (id 9) (at 64.135 94.234 0)
      (effects (font (size 1.27 1.27)) (justify left bottom) hide)
    )
    (pin "1")
    (pin "2")
  )

  (symbol (lib_id "sa800u-baseboard-hw:R_100k_0402") (at 53.975 63.754 270) (mirror x) (unit 1)
    (in_bom yes) (on_board yes) (fields_autoplaced)
    (property "Reference" "R57" (id 0) (at 55.88 59.944 90)
      (effects (font (size 1.524 1.524)) (justify left))
    )
    (property "Value" "R_100k_0402" (id 1) (at 50.165 63.754 0)
      (effects (font (size 1.524 1.524)) hide)
    )
    (property "Footprint" "sa800u-baseboard-hw-footprints:R_0402_1005Metric" (id 2) (at 59.055 58.674 0)
      (effects (font (size 1.524 1.524)) (justify left) hide)
    )
    (property "Datasheet" "https://www.bourns.com/docs/product-datasheets/cr.pdf" (id 3) (at 53.975 63.754 0)
      (effects (font (size 1.27 1.27)) hide)
    )
    (property "Manufacturer" "Bourns" (id 4) (at 64.135 58.674 0)
      (effects (font (size 1.524 1.524)) (justify left) hide)
    )
    (property "MPN" "CR0402-FX-1003GLF" (id 5) (at 61.595 58.674 0)
      (effects (font (size 1.524 1.524)) (justify left) hide)
    )
    (property "Val" "100k" (id 6) (at 55.88 63.1189 90)
      (effects (font (size 1.27 1.27)) (justify left))
    )
    (property "License" "Apache-2.0" (id 7) (at 28.575 43.434 0)
      (effects (font (size 1.27 1.27) (thickness 0.15)) (justify left bottom) hide)
    )
    (property "Author" "Antmicro" (id 8) (at 26.035 43.434 0)
      (effects (font (size 1.27 1.27) (thickness 0.15)) (justify left bottom) hide)
    )
    (property "Tolerance" "1%" (id 9) (at 43.815 43.434 0)
      (effects (font (size 1.27 1.27)) (justify left bottom) hide)
    )
    (pin "1")
    (pin "2")
  )

  (symbol (lib_id "sa800u-baseboard-hw:GND") (at 53.975 80.645 0) (mirror y) (unit 1)
    (in_bom yes) (on_board yes) (fields_autoplaced)
    (property "Reference" "#PWR041" (id 0) (at 53.975 86.995 0)
      (effects (font (size 1.27 1.27)) hide)
    )
    (property "Value" "GND" (id 1) (at 53.975 85.09 0))
    (property "Footprint" "" (id 2) (at 53.975 80.645 0)
      (effects (font (size 1.27 1.27)) hide)
    )
    (property "Datasheet" "" (id 3) (at 53.975 80.645 0)
      (effects (font (size 1.27 1.27)) hide)
    )
    (property "Author" "Antmicro" (id 4) (at 45.085 88.265 0)
      (effects (font (size 1.27 1.27) (thickness 0.15)) (justify left bottom) hide)
    )
    (property "License" "Apache-2.0" (id 5) (at 45.085 90.805 0)
      (effects (font (size 1.27 1.27) (thickness 0.15)) (justify left bottom) hide)
    )
    (pin "1")
  )

  (symbol (lib_id "sa800u-baseboard-hw:C_100n_0402") (at 39.37 66.04 0) (mirror x) (unit 1)
    (in_bom yes) (on_board yes) (fields_autoplaced)
    (property "Reference" "C60" (id 0) (at 41.9163 58.42 0)
      (effects (font (size 1.524 1.524)))
    )
    (property "Value" "C_100n_0402" (id 1) (at 39.37 62.23 0)
      (effects (font (size 1.524 1.524)) hide)
    )
    (property "Footprint" "sa800u-baseboard-hw-footprints:C_0402_1005Metric" (id 2) (at 44.45 71.12 0)
      (effects (font (size 1.524 1.524)) (justify left) hide)
    )
    (property "Datasheet" "https://search.murata.co.jp/Ceramy/image/img/A01X/G101/ENG/GRM155R61H104KE14-01.pdf" (id 3) (at 39.37 66.04 0)
      (effects (font (size 1.27 1.27)) hide)
    )
    (property "Manufacturer" "Murata" (id 4) (at 44.45 76.2 0)
      (effects (font (size 1.524 1.524)) (justify left) hide)
    )
    (property "MPN" "GRM155R61H104KE14D" (id 5) (at 44.45 73.66 0)
      (effects (font (size 1.524 1.524)) (justify left) hide)
    )
    (property "Val" "100n" (id 6) (at 41.9163 62.23 0))
    (property "License" "Apache-2.0" (id 7) (at 59.69 43.18 0)
      (effects (font (size 1.27 1.27) (thickness 0.15)) (justify left bottom) hide)
    )
    (property "Author" "Antmicro" (id 8) (at 59.69 40.64 0)
      (effects (font (size 1.27 1.27) (thickness 0.15)) (justify left bottom) hide)
    )
    (property "Voltage" "50V" (id 9) (at 59.69 38.1 0)
      (effects (font (size 1.27 1.27)) (justify left bottom) hide)
    )
    (property "Dielectric" "X5R" (id 10) (at 59.69 35.56 0)
      (effects (font (size 1.27 1.27)) (justify left bottom) hide)
    )
    (pin "1")
    (pin "2")
  )

  (symbol (lib_id "sa800u-baseboard-hw:C_100n_0402") (at 39.37 71.12 0) (mirror x) (unit 1)
    (in_bom yes) (on_board yes) (fields_autoplaced)
    (property "Reference" "C61" (id 0) (at 41.9163 76.2 0)
      (effects (font (size 1.524 1.524)))
    )
    (property "Value" "C_100n_0402" (id 1) (at 39.37 67.31 0)
      (effects (font (size 1.524 1.524)) hide)
    )
    (property "Footprint" "sa800u-baseboard-hw-footprints:C_0402_1005Metric" (id 2) (at 44.45 76.2 0)
      (effects (font (size 1.524 1.524)) (justify left) hide)
    )
    (property "Datasheet" "https://search.murata.co.jp/Ceramy/image/img/A01X/G101/ENG/GRM155R61H104KE14-01.pdf" (id 3) (at 39.37 71.12 0)
      (effects (font (size 1.27 1.27)) hide)
    )
    (property "Manufacturer" "Murata" (id 4) (at 44.45 81.28 0)
      (effects (font (size 1.524 1.524)) (justify left) hide)
    )
    (property "MPN" "GRM155R61H104KE14D" (id 5) (at 44.45 78.74 0)
      (effects (font (size 1.524 1.524)) (justify left) hide)
    )
    (property "Val" "100n" (id 6) (at 41.9163 78.74 0))
    (property "License" "Apache-2.0" (id 7) (at 59.69 48.26 0)
      (effects (font (size 1.27 1.27) (thickness 0.15)) (justify left bottom) hide)
    )
    (property "Author" "Antmicro" (id 8) (at 59.69 45.72 0)
      (effects (font (size 1.27 1.27) (thickness 0.15)) (justify left bottom) hide)
    )
    (property "Voltage" "50V" (id 9) (at 59.69 43.18 0)
      (effects (font (size 1.27 1.27)) (justify left bottom) hide)
    )
    (property "Dielectric" "X5R" (id 10) (at 59.69 40.64 0)
      (effects (font (size 1.27 1.27)) (justify left bottom) hide)
    )
    (pin "1")
    (pin "2")
  )

  (symbol (lib_id "sa800u-baseboard-hw:C_100n_0402") (at 289.179 62.23 0) (unit 1)
    (in_bom yes) (on_board yes)
    (property "Reference" "C83" (id 0) (at 286.131 61.087 0)
      (effects (font (size 1.524 1.524)))
    )
    (property "Value" "C_100n_0402" (id 1) (at 289.179 66.04 0)
      (effects (font (size 1.524 1.524)) hide)
    )
    (property "Footprint" "sa800u-baseboard-hw-footprints:C_0402_1005Metric" (id 2) (at 294.259 57.15 0)
      (effects (font (size 1.524 1.524)) (justify left) hide)
    )
    (property "Datasheet" "https://search.murata.co.jp/Ceramy/image/img/A01X/G101/ENG/GRM155R61H104KE14-01.pdf" (id 3) (at 289.179 62.23 0)
      (effects (font (size 1.27 1.27)) hide)
    )
    (property "Manufacturer" "Murata" (id 4) (at 294.259 52.07 0)
      (effects (font (size 1.524 1.524)) (justify left) hide)
    )
    (property "MPN" "GRM155R61H104KE14D" (id 5) (at 294.259 54.61 0)
      (effects (font (size 1.524 1.524)) (justify left) hide)
    )
    (property "Val" "100n" (id 6) (at 294.894 61.087 0))
    (property "License" "Apache-2.0" (id 7) (at 309.499 85.09 0)
      (effects (font (size 1.27 1.27) (thickness 0.15)) (justify left bottom) hide)
    )
    (property "Author" "Antmicro" (id 8) (at 309.499 87.63 0)
      (effects (font (size 1.27 1.27) (thickness 0.15)) (justify left bottom) hide)
    )
    (property "Voltage" "50V" (id 9) (at 309.499 90.17 0)
      (effects (font (size 1.27 1.27)) (justify left bottom) hide)
    )
    (property "Dielectric" "X5R" (id 10) (at 309.499 92.71 0)
      (effects (font (size 1.27 1.27)) (justify left bottom) hide)
    )
    (pin "1")
    (pin "2")
  )

  (symbol (lib_id "sa800u-baseboard-hw:C_100n_0402") (at 286.639 64.77 0) (unit 1)
    (in_bom yes) (on_board yes)
    (property "Reference" "C79" (id 0) (at 286.131 63.754 0)
      (effects (font (size 1.524 1.524)))
    )
    (property "Value" "C_100n_0402" (id 1) (at 286.639 68.58 0)
      (effects (font (size 1.524 1.524)) hide)
    )
    (property "Footprint" "sa800u-baseboard-hw-footprints:C_0402_1005Metric" (id 2) (at 291.719 59.69 0)
      (effects (font (size 1.524 1.524)) (justify left) hide)
    )
    (property "Datasheet" "https://search.murata.co.jp/Ceramy/image/img/A01X/G101/ENG/GRM155R61H104KE14-01.pdf" (id 3) (at 286.639 64.77 0)
      (effects (font (size 1.27 1.27)) hide)
    )
    (property "Manufacturer" "Murata" (id 4) (at 291.719 54.61 0)
      (effects (font (size 1.524 1.524)) (justify left) hide)
    )
    (property "MPN" "GRM155R61H104KE14D" (id 5) (at 291.719 57.15 0)
      (effects (font (size 1.524 1.524)) (justify left) hide)
    )
    (property "Val" "100n" (id 6) (at 295.021 63.5 0))
    (property "License" "Apache-2.0" (id 7) (at 306.959 87.63 0)
      (effects (font (size 1.27 1.27) (thickness 0.15)) (justify left bottom) hide)
    )
    (property "Author" "Antmicro" (id 8) (at 306.959 90.17 0)
      (effects (font (size 1.27 1.27) (thickness 0.15)) (justify left bottom) hide)
    )
    (property "Voltage" "50V" (id 9) (at 306.959 92.71 0)
      (effects (font (size 1.27 1.27)) (justify left bottom) hide)
    )
    (property "Dielectric" "X5R" (id 10) (at 306.959 95.25 0)
      (effects (font (size 1.27 1.27)) (justify left bottom) hide)
    )
    (pin "1")
    (pin "2")
  )

  (symbol (lib_id "sa800u-baseboard-hw:C_100n_0402") (at 372.999 62.23 0) (unit 1)
    (in_bom yes) (on_board yes)
    (property "Reference" "C92" (id 0) (at 370.078 61.214 0)
      (effects (font (size 1.524 1.524)))
    )
    (property "Value" "C_100n_0402" (id 1) (at 372.999 66.04 0)
      (effects (font (size 1.524 1.524)) hide)
    )
    (property "Footprint" "sa800u-baseboard-hw-footprints:C_0402_1005Metric" (id 2) (at 378.079 57.15 0)
      (effects (font (size 1.524 1.524)) (justify left) hide)
    )
    (property "Datasheet" "https://search.murata.co.jp/Ceramy/image/img/A01X/G101/ENG/GRM155R61H104KE14-01.pdf" (id 3) (at 372.999 62.23 0)
      (effects (font (size 1.27 1.27)) hide)
    )
    (property "Manufacturer" "Murata" (id 4) (at 378.079 52.07 0)
      (effects (font (size 1.524 1.524)) (justify left) hide)
    )
    (property "MPN" "GRM155R61H104KE14D" (id 5) (at 378.079 54.61 0)
      (effects (font (size 1.524 1.524)) (justify left) hide)
    )
    (property "Val" "100n" (id 6) (at 379.095 61.214 0))
    (property "License" "Apache-2.0" (id 7) (at 393.319 85.09 0)
      (effects (font (size 1.27 1.27) (thickness 0.15)) (justify left bottom) hide)
    )
    (property "Author" "Antmicro" (id 8) (at 393.319 87.63 0)
      (effects (font (size 1.27 1.27) (thickness 0.15)) (justify left bottom) hide)
    )
    (property "Voltage" "50V" (id 9) (at 393.319 90.17 0)
      (effects (font (size 1.27 1.27)) (justify left bottom) hide)
    )
    (property "Dielectric" "X5R" (id 10) (at 393.319 92.71 0)
      (effects (font (size 1.27 1.27)) (justify left bottom) hide)
    )
    (pin "1")
    (pin "2")
  )

  (symbol (lib_id "sa800u-baseboard-hw:C_100n_0402") (at 370.459 64.77 0) (unit 1)
    (in_bom yes) (on_board yes)
    (property "Reference" "C87" (id 0) (at 370.078 63.627 0)
      (effects (font (size 1.524 1.524)))
    )
    (property "Value" "C_100n_0402" (id 1) (at 370.459 68.58 0)
      (effects (font (size 1.524 1.524)) hide)
    )
    (property "Footprint" "sa800u-baseboard-hw-footprints:C_0402_1005Metric" (id 2) (at 375.539 59.69 0)
      (effects (font (size 1.524 1.524)) (justify left) hide)
    )
    (property "Datasheet" "https://search.murata.co.jp/Ceramy/image/img/A01X/G101/ENG/GRM155R61H104KE14-01.pdf" (id 3) (at 370.459 64.77 0)
      (effects (font (size 1.27 1.27)) hide)
    )
    (property "Manufacturer" "Murata" (id 4) (at 375.539 54.61 0)
      (effects (font (size 1.524 1.524)) (justify left) hide)
    )
    (property "MPN" "GRM155R61H104KE14D" (id 5) (at 375.539 57.15 0)
      (effects (font (size 1.524 1.524)) (justify left) hide)
    )
    (property "Val" "100n" (id 6) (at 379.349 63.754 0))
    (property "License" "Apache-2.0" (id 7) (at 390.779 87.63 0)
      (effects (font (size 1.27 1.27) (thickness 0.15)) (justify left bottom) hide)
    )
    (property "Author" "Antmicro" (id 8) (at 390.779 90.17 0)
      (effects (font (size 1.27 1.27) (thickness 0.15)) (justify left bottom) hide)
    )
    (property "Voltage" "50V" (id 9) (at 390.779 92.71 0)
      (effects (font (size 1.27 1.27)) (justify left bottom) hide)
    )
    (property "Dielectric" "X5R" (id 10) (at 390.779 95.25 0)
      (effects (font (size 1.27 1.27)) (justify left bottom) hide)
    )
    (pin "1")
    (pin "2")
  )

  (symbol (lib_id "sa800u-baseboard-hw:C_100n_0402") (at 372.999 82.55 0) (unit 1)
    (in_bom yes) (on_board yes)
    (property "Reference" "C93" (id 0) (at 370.078 81.407 0)
      (effects (font (size 1.524 1.524)))
    )
    (property "Value" "C_100n_0402" (id 1) (at 372.999 86.36 0)
      (effects (font (size 1.524 1.524)) hide)
    )
    (property "Footprint" "sa800u-baseboard-hw-footprints:C_0402_1005Metric" (id 2) (at 378.079 77.47 0)
      (effects (font (size 1.524 1.524)) (justify left) hide)
    )
    (property "Datasheet" "https://search.murata.co.jp/Ceramy/image/img/A01X/G101/ENG/GRM155R61H104KE14-01.pdf" (id 3) (at 372.999 82.55 0)
      (effects (font (size 1.27 1.27)) hide)
    )
    (property "Manufacturer" "Murata" (id 4) (at 378.079 72.39 0)
      (effects (font (size 1.524 1.524)) (justify left) hide)
    )
    (property "MPN" "GRM155R61H104KE14D" (id 5) (at 378.079 74.93 0)
      (effects (font (size 1.524 1.524)) (justify left) hide)
    )
    (property "Val" "100n" (id 6) (at 378.968 81.407 0))
    (property "License" "Apache-2.0" (id 7) (at 393.319 105.41 0)
      (effects (font (size 1.27 1.27) (thickness 0.15)) (justify left bottom) hide)
    )
    (property "Author" "Antmicro" (id 8) (at 393.319 107.95 0)
      (effects (font (size 1.27 1.27) (thickness 0.15)) (justify left bottom) hide)
    )
    (property "Voltage" "50V" (id 9) (at 393.319 110.49 0)
      (effects (font (size 1.27 1.27)) (justify left bottom) hide)
    )
    (property "Dielectric" "X5R" (id 10) (at 393.319 113.03 0)
      (effects (font (size 1.27 1.27)) (justify left bottom) hide)
    )
    (pin "1")
    (pin "2")
  )

  (symbol (lib_id "sa800u-baseboard-hw:C_100n_0402") (at 370.459 85.09 0) (unit 1)
    (in_bom yes) (on_board yes)
    (property "Reference" "C88" (id 0) (at 369.951 84.074 0)
      (effects (font (size 1.524 1.524)))
    )
    (property "Value" "C_100n_0402" (id 1) (at 370.459 88.9 0)
      (effects (font (size 1.524 1.524)) hide)
    )
    (property "Footprint" "sa800u-baseboard-hw-footprints:C_0402_1005Metric" (id 2) (at 375.539 80.01 0)
      (effects (font (size 1.524 1.524)) (justify left) hide)
    )
    (property "Datasheet" "https://search.murata.co.jp/Ceramy/image/img/A01X/G101/ENG/GRM155R61H104KE14-01.pdf" (id 3) (at 370.459 85.09 0)
      (effects (font (size 1.27 1.27)) hide)
    )
    (property "Manufacturer" "Murata" (id 4) (at 375.539 74.93 0)
      (effects (font (size 1.524 1.524)) (justify left) hide)
    )
    (property "MPN" "GRM155R61H104KE14D" (id 5) (at 375.539 77.47 0)
      (effects (font (size 1.524 1.524)) (justify left) hide)
    )
    (property "Val" "100n" (id 6) (at 379.095 84.074 0))
    (property "License" "Apache-2.0" (id 7) (at 390.779 107.95 0)
      (effects (font (size 1.27 1.27) (thickness 0.15)) (justify left bottom) hide)
    )
    (property "Author" "Antmicro" (id 8) (at 390.779 110.49 0)
      (effects (font (size 1.27 1.27) (thickness 0.15)) (justify left bottom) hide)
    )
    (property "Voltage" "50V" (id 9) (at 390.779 113.03 0)
      (effects (font (size 1.27 1.27)) (justify left bottom) hide)
    )
    (property "Dielectric" "X5R" (id 10) (at 390.779 115.57 0)
      (effects (font (size 1.27 1.27)) (justify left bottom) hide)
    )
    (pin "1")
    (pin "2")
  )

  (symbol (lib_id "sa800u-baseboard-hw:FT232R_QFN") (at 89.916 123.825 0) (mirror y) (unit 1)
    (in_bom yes) (on_board yes) (fields_autoplaced)
    (property "Reference" "U5" (id 0) (at 77.216 115.57 0)
      (effects (font (size 1.524 1.524)))
    )
    (property "Value" "FT232R_QFN" (id 1) (at 77.216 119.634 0)
      (effects (font (size 1.524 1.524)) hide)
    )
    (property "Footprint" "sa800u-baseboard-hw-footprints:QFN-32-1EP_5x5mm" (id 2) (at 84.836 118.745 0)
      (effects (font (size 1.524 1.524)) (justify left) hide)
    )
    (property "Datasheet" "https://www.ftdichip.com/Support/Documents/DataSheets/ICs/DS_FT232R.pdf" (id 3) (at 84.836 116.205 0)
      (effects (font (size 1.524 1.524)) (justify left) hide)
    )
    (property "Manufacturer" "FTDI" (id 4) (at 84.836 95.885 0)
      (effects (font (size 1.524 1.524)) (justify left) hide)
    )
    (property "MPN" "FT232RQ-REEL" (id 5) (at 77.216 119.38 0)
      (effects (font (size 1.524 1.524)))
    )
    (property "Author" "Antmicro" (id 6) (at 49.276 144.145 0)
      (effects (font (size 1.27 1.27) (thickness 0.15)) (justify left bottom) hide)
    )
    (property "License" "Apache-2.0" (id 7) (at 49.276 146.685 0)
      (effects (font (size 1.27 1.27) (thickness 0.15)) (justify left bottom) hide)
    )
    (pin "1")
    (pin "10")
    (pin "11")
    (pin "12")
    (pin "13")
    (pin "14")
    (pin "15")
    (pin "16")
    (pin "17")
    (pin "18")
    (pin "19")
    (pin "2")
    (pin "20")
    (pin "21")
    (pin "22")
    (pin "23")
    (pin "24")
    (pin "25")
    (pin "26")
    (pin "27")
    (pin "28")
    (pin "29")
    (pin "3")
    (pin "30")
    (pin "31")
    (pin "32")
    (pin "33")
    (pin "4")
    (pin "5")
    (pin "6")
    (pin "7")
    (pin "8")
    (pin "9")
  )

  (symbol (lib_id "sa800u-baseboard-hw:GND") (at 315.595 160.02 0) (unit 1)
    (in_bom yes) (on_board yes) (fields_autoplaced)
    (property "Reference" "#PWR070" (id 0) (at 315.595 166.37 0)
      (effects (font (size 1.27 1.27)) hide)
    )
    (property "Value" "GND" (id 1) (at 315.595 165.1 0))
    (property "Footprint" "" (id 2) (at 315.595 160.02 0)
      (effects (font (size 1.27 1.27)) hide)
    )
    (property "Datasheet" "" (id 3) (at 315.595 160.02 0)
      (effects (font (size 1.27 1.27)) hide)
    )
    (property "Author" "Antmicro" (id 4) (at 324.485 167.64 0)
      (effects (font (size 1.27 1.27) (thickness 0.15)) (justify left bottom) hide)
    )
    (property "License" "Apache-2.0" (id 5) (at 324.485 170.18 0)
      (effects (font (size 1.27 1.27) (thickness 0.15)) (justify left bottom) hide)
    )
    (pin "1")
  )

  (symbol (lib_id "sa800u-baseboard-hw:GND") (at 346.71 160.02 0) (unit 1)
    (in_bom yes) (on_board yes) (fields_autoplaced)
    (property "Reference" "#PWR078" (id 0) (at 346.71 166.37 0)
      (effects (font (size 1.27 1.27)) hide)
    )
    (property "Value" "GND" (id 1) (at 349.25 161.2899 0)
      (effects (font (size 1.27 1.27)) (justify left))
    )
    (property "Footprint" "" (id 2) (at 346.71 160.02 0)
      (effects (font (size 1.27 1.27)) hide)
    )
    (property "Datasheet" "" (id 3) (at 346.71 160.02 0)
      (effects (font (size 1.27 1.27)) hide)
    )
    (property "Author" "Antmicro" (id 4) (at 355.6 167.64 0)
      (effects (font (size 1.27 1.27) (thickness 0.15)) (justify left bottom) hide)
    )
    (property "License" "Apache-2.0" (id 5) (at 355.6 170.18 0)
      (effects (font (size 1.27 1.27) (thickness 0.15)) (justify left bottom) hide)
    )
    (pin "1")
  )

  (symbol (lib_id "sa800u-baseboard-hw:C_47u_0603") (at 370.205 43.815 270) (unit 1)
    (in_bom yes) (on_board yes) (fields_autoplaced)
    (property "Reference" "C89" (id 0) (at 373.253 45.0913 90)
      (effects (font (size 1.524 1.524)) (justify left))
    )
    (property "Value" "C_47u_0603" (id 1) (at 366.395 43.815 0)
      (effects (font (size 1.524 1.524)) hide)
    )
    (property "Footprint" "sa800u-baseboard-hw-footprints:C_0603_1608Metric" (id 2) (at 375.285 48.895 0)
      (effects (font (size 1.524 1.524)) (justify left) hide)
    )
    (property "Datasheet" " " (id 3) (at 370.205 43.815 0)
      (effects (font (size 1.27 1.27)) hide)
    )
    (property "Manufacturer" "Murata" (id 4) (at 380.365 48.895 0)
      (effects (font (size 1.524 1.524)) (justify left) hide)
    )
    (property "MPN" "GRM188R60J476ME15D" (id 5) (at 377.825 48.895 0)
      (effects (font (size 1.524 1.524)) (justify left) hide)
    )
    (property "Val" "47u" (id 6) (at 373.253 48.2662 90)
      (effects (font (size 1.27 1.27)) (justify left))
    )
    (property "License" "Apache-2.0" (id 7) (at 347.345 64.135 0)
      (effects (font (size 1.27 1.27) (thickness 0.15)) (justify left bottom) hide)
    )
    (property "Author" "Antmicro" (id 8) (at 344.805 64.135 0)
      (effects (font (size 1.27 1.27) (thickness 0.15)) (justify left bottom) hide)
    )
    (property "Voltage" "" (id 9) (at 342.265 64.135 0)
      (effects (font (size 1.27 1.27)) (justify left bottom) hide)
    )
    (property "Dielectric" "" (id 10) (at 339.725 64.135 0)
      (effects (font (size 1.27 1.27)) (justify left bottom) hide)
    )
    (pin "1")
    (pin "2")
  )

  (symbol (lib_id "sa800u-baseboard-hw:C_47u_0603") (at 380.365 43.815 270) (unit 1)
    (in_bom yes) (on_board yes) (fields_autoplaced)
    (property "Reference" "C96" (id 0) (at 383.667 45.0913 90)
      (effects (font (size 1.524 1.524)) (justify left))
    )
    (property "Value" "C_47u_0603" (id 1) (at 376.555 43.815 0)
      (effects (font (size 1.524 1.524)) hide)
    )
    (property "Footprint" "sa800u-baseboard-hw-footprints:C_0603_1608Metric" (id 2) (at 385.445 48.895 0)
      (effects (font (size 1.524 1.524)) (justify left) hide)
    )
    (property "Datasheet" " " (id 3) (at 380.365 43.815 0)
      (effects (font (size 1.27 1.27)) hide)
    )
    (property "Manufacturer" "Murata" (id 4) (at 390.525 48.895 0)
      (effects (font (size 1.524 1.524)) (justify left) hide)
    )
    (property "MPN" "GRM188R60J476ME15D" (id 5) (at 387.985 48.895 0)
      (effects (font (size 1.524 1.524)) (justify left) hide)
    )
    (property "Val" "47u" (id 6) (at 383.667 48.2662 90)
      (effects (font (size 1.27 1.27)) (justify left))
    )
    (property "License" "Apache-2.0" (id 7) (at 357.505 64.135 0)
      (effects (font (size 1.27 1.27) (thickness 0.15)) (justify left bottom) hide)
    )
    (property "Author" "Antmicro" (id 8) (at 354.965 64.135 0)
      (effects (font (size 1.27 1.27) (thickness 0.15)) (justify left bottom) hide)
    )
    (property "Voltage" "" (id 9) (at 352.425 64.135 0)
      (effects (font (size 1.27 1.27)) (justify left bottom) hide)
    )
    (property "Dielectric" "" (id 10) (at 349.885 64.135 0)
      (effects (font (size 1.27 1.27)) (justify left bottom) hide)
    )
    (pin "1")
    (pin "2")
  )

  (symbol (lib_name "12401598E4_2A_2") (lib_id "sa800u-baseboard-hw:12401598E4_2A") (at 344.043 130.81 0) (mirror y) (unit 1)
    (in_bom yes) (on_board yes) (fields_autoplaced)
    (property "Reference" "J5" (id 0) (at 332.6765 118.11 0))
    (property "Value" "12401598E4_2A" (id 1) (at 332.6765 120.65 0))
    (property "Footprint" "sa800u-baseboard-hw-footprints:USB-C_12401610E4_2A" (id 2) (at 338.963 125.73 0)
      (effects (font (size 1.524 1.524)) (justify left) hide)
    )
    (property "Datasheet" "http://www.amphenol-icc.com/media/wysiwyg/files/drawing/12401598xxx2a.pdf" (id 3) (at 338.963 123.19 0)
      (effects (font (size 1.524 1.524)) (justify left) hide)
    )
    (property "MPN" "12401598E4#2A" (id 4) (at 338.963 118.11 0)
      (effects (font (size 1.524 1.524)) (justify left) hide)
    )
    (property "Manufacturer" "Amphenol" (id 5) (at 338.963 102.87 0)
      (effects (font (size 1.524 1.524)) (justify left) hide)
    )
    (property "Author" "Antmicro" (id 6) (at 311.023 148.59 0)
      (effects (font (size 1.27 1.27) (thickness 0.15)) (justify left bottom) hide)
    )
    (property "License" "Apache-2.0" (id 7) (at 311.023 151.13 0)
      (effects (font (size 1.27 1.27) (thickness 0.15)) (justify left bottom) hide)
    )
    (pin "A1")
    (pin "A10")
    (pin "A11")
    (pin "A12")
    (pin "A2")
    (pin "A3")
    (pin "A4")
    (pin "A5")
    (pin "A6")
    (pin "A7")
    (pin "A8")
    (pin "A9")
    (pin "B1")
    (pin "B10")
    (pin "B11")
    (pin "B12")
    (pin "B2")
    (pin "B3")
    (pin "B4")
    (pin "B5")
    (pin "B6")
    (pin "B7")
    (pin "B8")
    (pin "B9")
    (pin "SH")
  )

  (symbol (lib_id "sa800u-baseboard-hw:GND") (at 317.5 130.81 270) (unit 1)
    (in_bom yes) (on_board yes) (fields_autoplaced)
    (property "Reference" "#PWR073" (id 0) (at 311.15 130.81 0)
      (effects (font (size 1.27 1.27)) hide)
    )
    (property "Value" "GND" (id 1) (at 313.69 130.8099 90)
      (effects (font (size 1.27 1.27)) (justify right))
    )
    (property "Footprint" "" (id 2) (at 317.5 130.81 0)
      (effects (font (size 1.27 1.27)) hide)
    )
    (property "Datasheet" "" (id 3) (at 317.5 130.81 0)
      (effects (font (size 1.27 1.27)) hide)
    )
    (property "Author" "Antmicro" (id 4) (at 309.88 139.7 0)
      (effects (font (size 1.27 1.27) (thickness 0.15)) (justify left bottom) hide)
    )
    (property "License" "Apache-2.0" (id 5) (at 307.34 139.7 0)
      (effects (font (size 1.27 1.27) (thickness 0.15)) (justify left bottom) hide)
    )
    (pin "1")
  )

  (symbol (lib_id "sa800u-baseboard-hw:NX3DV42GU") (at 97.79 60.96 0) (mirror y) (unit 1)
    (in_bom yes) (on_board yes) (fields_autoplaced)
    (property "Reference" "U7" (id 0) (at 88.9 53.34 0))
    (property "Value" "NX3DV42GU" (id 1) (at 88.9 55.88 0))
    (property "Footprint" "sa800u-baseboard-hw-footprints:XQFN-10-1.4x1.8mm_P0.4mm" (id 2) (at 97.79 81.28 0)
      (effects (font (size 1.27 1.27)) hide)
    )
    (property "Datasheet" "https://www.nxp.com/docs/en/data-sheet/NX3DV42.pdf" (id 3) (at 97.79 63.5 0)
      (effects (font (size 1.27 1.27)) hide)
    )
    (property "MPN" "NX3DV42GU,115" (id 4) (at 97.79 48.5394 0)
      (effects (font (size 1.27 1.27)) hide)
    )
    (property "Manufacturer" "NXP" (id 5) (at 97.79 86.36 0)
      (effects (font (size 1.27 1.27)) hide)
    )
    (property "Author" "Antmicro" (id 6) (at 67.31 78.74 0)
      (effects (font (size 1.27 1.27) (thickness 0.15)) (justify left bottom) hide)
    )
    (property "License" "Apache-2.0" (id 7) (at 67.31 81.28 0)
      (effects (font (size 1.27 1.27) (thickness 0.15)) (justify left bottom) hide)
    )
    (pin "1")
    (pin "10")
    (pin "2")
    (pin "3")
    (pin "4")
    (pin "5")
    (pin "6")
    (pin "7")
    (pin "8")
    (pin "9")
  )

  (symbol (lib_id "sa800u-baseboard-hw:GND") (at 347.98 130.81 90) (mirror x) (unit 1)
    (in_bom yes) (on_board yes) (fields_autoplaced)
    (property "Reference" "#PWR080" (id 0) (at 354.33 130.81 0)
      (effects (font (size 1.27 1.27)) hide)
    )
    (property "Value" "GND" (id 1) (at 351.79 130.8099 90)
      (effects (font (size 1.27 1.27)) (justify right))
    )
    (property "Footprint" "" (id 2) (at 347.98 130.81 0)
      (effects (font (size 1.27 1.27)) hide)
    )
    (property "Datasheet" "" (id 3) (at 347.98 130.81 0)
      (effects (font (size 1.27 1.27)) hide)
    )
    (property "Author" "Antmicro" (id 4) (at 355.6 139.7 0)
      (effects (font (size 1.27 1.27) (thickness 0.15)) (justify left bottom) hide)
    )
    (property "License" "Apache-2.0" (id 5) (at 358.14 139.7 0)
      (effects (font (size 1.27 1.27) (thickness 0.15)) (justify left bottom) hide)
    )
    (pin "1")
  )

  (symbol (lib_id "sa800u-baseboard-hw:GND") (at 380.365 50.165 0) (unit 1)
    (in_bom yes) (on_board yes) (fields_autoplaced)
    (property "Reference" "#PWR081" (id 0) (at 380.365 56.515 0)
      (effects (font (size 1.27 1.27)) hide)
    )
    (property "Value" "GND" (id 1) (at 380.365 54.61 0))
    (property "Footprint" "" (id 2) (at 380.365 50.165 0)
      (effects (font (size 1.27 1.27)) hide)
    )
    (property "Datasheet" "" (id 3) (at 380.365 50.165 0)
      (effects (font (size 1.27 1.27)) hide)
    )
    (property "Author" "Antmicro" (id 4) (at 389.255 57.785 0)
      (effects (font (size 1.27 1.27) (thickness 0.15)) (justify left bottom) hide)
    )
    (property "License" "Apache-2.0" (id 5) (at 389.255 60.325 0)
      (effects (font (size 1.27 1.27) (thickness 0.15)) (justify left bottom) hide)
    )
    (pin "1")
  )

  (symbol (lib_id "sa800u-baseboard-hw:12401598E4_2A") (at 343.408 205.105 0) (mirror y) (unit 1)
    (in_bom yes) (on_board yes) (fields_autoplaced)
    (property "Reference" "J4" (id 0) (at 332.0415 191.77 0))
    (property "Value" "12401598E4_2A" (id 1) (at 332.0415 194.31 0))
    (property "Footprint" "sa800u-baseboard-hw-footprints:USB-C_12401610E4_2A" (id 2) (at 338.328 200.025 0)
      (effects (font (size 1.524 1.524)) (justify left) hide)
    )
    (property "Datasheet" "http://www.amphenol-icc.com/media/wysiwyg/files/drawing/12401598xxx2a.pdf" (id 3) (at 338.328 197.485 0)
      (effects (font (size 1.524 1.524)) (justify left) hide)
    )
    (property "MPN" "12401598E4#2A" (id 4) (at 338.328 192.405 0)
      (effects (font (size 1.524 1.524)) (justify left) hide)
    )
    (property "Manufacturer" "Amphenol" (id 5) (at 338.328 177.165 0)
      (effects (font (size 1.524 1.524)) (justify left) hide)
    )
    (property "Author" "Antmicro" (id 6) (at 310.388 222.885 0)
      (effects (font (size 1.27 1.27) (thickness 0.15)) (justify left bottom) hide)
    )
    (property "License" "Apache-2.0" (id 7) (at 310.388 225.425 0)
      (effects (font (size 1.27 1.27) (thickness 0.15)) (justify left bottom) hide)
    )
    (pin "A1")
    (pin "A10")
    (pin "A11")
    (pin "A12")
    (pin "A2")
    (pin "A3")
    (pin "A4")
    (pin "A5")
    (pin "A6")
    (pin "A7")
    (pin "A8")
    (pin "A9")
    (pin "B1")
    (pin "B10")
    (pin "B11")
    (pin "B12")
    (pin "B2")
    (pin "B3")
    (pin "B4")
    (pin "B5")
    (pin "B6")
    (pin "B7")
    (pin "B8")
    (pin "B9")
    (pin "SH")
  )

  (symbol (lib_name "12401598E4_2A_1") (lib_id "sa800u-baseboard-hw:12401598E4_2A") (at 342.773 59.69 0) (mirror y) (unit 1)
    (in_bom yes) (on_board yes) (fields_autoplaced)
    (property "Reference" "J3" (id 0) (at 331.4065 46.99 0))
    (property "Value" "12401598E4_2A" (id 1) (at 331.4065 49.53 0))
    (property "Footprint" "sa800u-baseboard-hw-footprints:USB-C_12401610E4_2A" (id 2) (at 337.693 54.61 0)
      (effects (font (size 1.524 1.524)) (justify left) hide)
    )
    (property "Datasheet" "http://www.amphenol-icc.com/media/wysiwyg/files/drawing/12401598xxx2a.pdf" (id 3) (at 337.693 52.07 0)
      (effects (font (size 1.524 1.524)) (justify left) hide)
    )
    (property "MPN" "12401598E4#2A" (id 4) (at 337.693 46.99 0)
      (effects (font (size 1.524 1.524)) (justify left) hide)
    )
    (property "Manufacturer" "Amphenol" (id 5) (at 337.693 31.75 0)
      (effects (font (size 1.524 1.524)) (justify left) hide)
    )
    (property "Author" "Antmicro" (id 6) (at 309.753 77.47 0)
      (effects (font (size 1.27 1.27) (thickness 0.15)) (justify left bottom) hide)
    )
    (property "License" "Apache-2.0" (id 7) (at 309.753 80.01 0)
      (effects (font (size 1.27 1.27) (thickness 0.15)) (justify left bottom) hide)
    )
    (pin "A1")
    (pin "A10")
    (pin "A11")
    (pin "A12")
    (pin "A2")
    (pin "A3")
    (pin "A4")
    (pin "A5")
    (pin "A6")
    (pin "A7")
    (pin "A8")
    (pin "A9")
    (pin "B1")
    (pin "B10")
    (pin "B11")
    (pin "B12")
    (pin "B2")
    (pin "B3")
    (pin "B4")
    (pin "B5")
    (pin "B6")
    (pin "B7")
    (pin "B8")
    (pin "B9")
    (pin "SH")
  )

  (symbol (lib_id "sa800u-baseboard-hw:TP_0.75mm_SMD") (at 44.577 129.794 90) (mirror x) (unit 1)
    (in_bom yes) (on_board yes) (fields_autoplaced)
    (property "Reference" "TP99" (id 0) (at 45.974 132.9691 90)
      (effects (font (size 1.27 1.27)) (justify right))
    )
    (property "Value" "TP_0.75mm_SMD" (id 1) (at 47.117 129.794 0)
      (effects (font (size 1.27 1.27)) hide)
    )
    (property "Footprint" "sa800u-baseboard-hw-footprints:TP_SMD_0.75mm" (id 2) (at 39.497 134.874 0)
      (effects (font (size 1.524 1.524)) (justify left) hide)
    )
    (property "Datasheet" "" (id 3) (at 36.957 134.874 0)
      (effects (font (size 1.524 1.524)) (justify left) hide)
    )
    (property "MPN" "" (id 4) (at 59.817 147.574 0)
      (effects (font (size 1.27 1.27) (thickness 0.15)) (justify left bottom) hide)
    )
    (property "Manufacturer" "" (id 5) (at 62.357 147.574 0)
      (effects (font (size 1.27 1.27) (thickness 0.15)) (justify left bottom) hide)
    )
    (property "Author" "Antmicro" (id 6) (at 64.897 147.574 0)
      (effects (font (size 1.27 1.27) (thickness 0.15)) (justify left bottom) hide)
    )
    (property "License" "Apache-2.0" (id 7) (at 67.437 147.574 0)
      (effects (font (size 1.27 1.27) (thickness 0.15)) (justify left bottom) hide)
    )
    (pin "1")
  )

  (symbol (lib_id "sa800u-baseboard-hw:GND") (at 229.235 80.645 0) (unit 1)
    (in_bom yes) (on_board yes) (fields_autoplaced)
    (property "Reference" "#PWR065" (id 0) (at 229.235 86.995 0)
      (effects (font (size 1.27 1.27)) hide)
    )
    (property "Value" "GND" (id 1) (at 227.33 81.9149 0)
      (effects (font (size 1.27 1.27)) (justify right))
    )
    (property "Footprint" "" (id 2) (at 229.235 80.645 0)
      (effects (font (size 1.27 1.27)) hide)
    )
    (property "Datasheet" "" (id 3) (at 229.235 80.645 0)
      (effects (font (size 1.27 1.27)) hide)
    )
    (property "Author" "Antmicro" (id 4) (at 238.125 88.265 0)
      (effects (font (size 1.27 1.27) (thickness 0.15)) (justify left bottom) hide)
    )
    (property "License" "Apache-2.0" (id 5) (at 238.125 90.805 0)
      (effects (font (size 1.27 1.27) (thickness 0.15)) (justify left bottom) hide)
    )
    (pin "1")
  )

  (symbol (lib_id "sa800u-baseboard-hw:PUSB3F96X_PASS") (at 247.015 77.47 270) (unit 1)
    (in_bom yes) (on_board yes) (fields_autoplaced)
    (property "Reference" "D10" (id 0) (at 241.935 93.98 90)
      (effects (font (size 1.524 1.524)))
    )
    (property "Value" "PUSB3F96X_PASS" (id 1) (at 241.935 97.79 90)
      (effects (font (size 1.524 1.524)))
    )
    (property "Footprint" "sa800u-baseboard-hw-footprints:Nexperia_DFN-10_2.5x1mm_P0.5mm" (id 2) (at 233.045 82.55 0)
      (effects (font (size 1.524 1.524)) hide)
    )
    (property "Datasheet" "https://pl.mouser.com/datasheet/2/916/PUSB3F96-1600324.pdf" (id 3) (at 247.015 77.47 0)
      (effects (font (size 1.524 1.524)) hide)
    )
    (property "Manufacturer" "Nexperia" (id 4) (at 230.505 82.55 0)
      (effects (font (size 1.27 1.27)) hide)
    )
    (property "MPN" "PUSB3F96X" (id 5) (at 230.505 82.55 0)
      (effects (font (size 1.27 1.27)) hide)
    )
    (property "Author" "Antmicro" (id 6) (at 229.235 102.87 0)
      (effects (font (size 1.27 1.27) (thickness 0.15)) (justify left bottom) hide)
    )
    (property "License" "Apache-2.0" (id 7) (at 226.695 102.87 0)
      (effects (font (size 1.27 1.27) (thickness 0.15)) (justify left bottom) hide)
    )
    (pin "1")
    (pin "10")
    (pin "2")
    (pin "3")
    (pin "4")
    (pin "5")
    (pin "6")
    (pin "7")
    (pin "8")
    (pin "9")
  )

  (symbol (lib_id "sa800u-baseboard-hw:GND") (at 204.597 80.645 0) (unit 1)
    (in_bom yes) (on_board yes) (fields_autoplaced)
    (property "Reference" "#PWR061" (id 0) (at 204.597 86.995 0)
      (effects (font (size 1.27 1.27)) hide)
    )
    (property "Value" "GND" (id 1) (at 202.692 81.9149 0)
      (effects (font (size 1.27 1.27)) (justify right))
    )
    (property "Footprint" "" (id 2) (at 204.597 80.645 0)
      (effects (font (size 1.27 1.27)) hide)
    )
    (property "Datasheet" "" (id 3) (at 204.597 80.645 0)
      (effects (font (size 1.27 1.27)) hide)
    )
    (property "Author" "Antmicro" (id 4) (at 213.487 88.265 0)
      (effects (font (size 1.27 1.27) (thickness 0.15)) (justify left bottom) hide)
    )
    (property "License" "Apache-2.0" (id 5) (at 213.487 90.805 0)
      (effects (font (size 1.27 1.27) (thickness 0.15)) (justify left bottom) hide)
    )
    (pin "1")
  )

  (symbol (lib_id "sa800u-baseboard-hw:PUSB3F96X_PASS") (at 220.345 77.47 270) (unit 1)
    (in_bom yes) (on_board yes) (fields_autoplaced)
    (property "Reference" "D9" (id 0) (at 215.265 93.98 90)
      (effects (font (size 1.524 1.524)))
    )
    (property "Value" "PUSB3F96X_PASS" (id 1) (at 215.265 97.79 90)
      (effects (font (size 1.524 1.524)))
    )
    (property "Footprint" "sa800u-baseboard-hw-footprints:Nexperia_DFN-10_2.5x1mm_P0.5mm" (id 2) (at 206.375 82.55 0)
      (effects (font (size 1.524 1.524)) hide)
    )
    (property "Datasheet" "https://pl.mouser.com/datasheet/2/916/PUSB3F96-1600324.pdf" (id 3) (at 220.345 77.47 0)
      (effects (font (size 1.524 1.524)) hide)
    )
    (property "Manufacturer" "Nexperia" (id 4) (at 203.835 82.55 0)
      (effects (font (size 1.27 1.27)) hide)
    )
    (property "MPN" "PUSB3F96X" (id 5) (at 203.835 82.55 0)
      (effects (font (size 1.27 1.27)) hide)
    )
    (property "Author" "Antmicro" (id 6) (at 202.565 102.87 0)
      (effects (font (size 1.27 1.27) (thickness 0.15)) (justify left bottom) hide)
    )
    (property "License" "Apache-2.0" (id 7) (at 200.025 102.87 0)
      (effects (font (size 1.27 1.27) (thickness 0.15)) (justify left bottom) hide)
    )
    (pin "1")
    (pin "10")
    (pin "2")
    (pin "3")
    (pin "4")
    (pin "5")
    (pin "6")
    (pin "7")
    (pin "8")
    (pin "9")
  )

  (symbol (lib_id "sa800u-baseboard-hw:PUSB3F96X_PASS") (at 287.655 258.445 270) (unit 1)
    (in_bom yes) (on_board yes)
    (property "Reference" "D12" (id 0) (at 275.209 272.796 90)
      (effects (font (size 1.524 1.524)) (justify left))
    )
    (property "Value" "PUSB3F96X_PASS" (id 1) (at 275.336 275.082 90)
      (effects (font (size 1.524 1.524)) (justify left))
    )
    (property "Footprint" "sa800u-baseboard-hw-footprints:Nexperia_DFN-10_2.5x1mm_P0.5mm" (id 2) (at 273.685 263.525 0)
      (effects (font (size 1.524 1.524)) hide)
    )
    (property "Datasheet" "https://pl.mouser.com/datasheet/2/916/PUSB3F96-1600324.pdf" (id 3) (at 287.655 258.445 0)
      (effects (font (size 1.524 1.524)) hide)
    )
    (property "Manufacturer" "Nexperia" (id 4) (at 271.145 263.525 0)
      (effects (font (size 1.27 1.27)) hide)
    )
    (property "MPN" "PUSB3F96X" (id 5) (at 271.145 263.525 0)
      (effects (font (size 1.27 1.27)) hide)
    )
    (property "Author" "Antmicro" (id 6) (at 269.875 283.845 0)
      (effects (font (size 1.27 1.27) (thickness 0.15)) (justify left bottom) hide)
    )
    (property "License" "Apache-2.0" (id 7) (at 267.335 283.845 0)
      (effects (font (size 1.27 1.27) (thickness 0.15)) (justify left bottom) hide)
    )
    (pin "1")
    (pin "10")
    (pin "2")
    (pin "3")
    (pin "4")
    (pin "5")
    (pin "6")
    (pin "7")
    (pin "8")
    (pin "9")
  )

  (symbol (lib_id "sa800u-baseboard-hw:TP_0.75mm_SMD") (at 44.577 125.222 270) (mirror x) (unit 1)
    (in_bom yes) (on_board yes) (fields_autoplaced)
    (property "Reference" "TP100" (id 0) (at 46.228 122.0471 90)
      (effects (font (size 1.27 1.27)) (justify left))
    )
    (property "Value" "TP_0.75mm_SMD" (id 1) (at 42.037 125.222 0)
      (effects (font (size 1.27 1.27)) hide)
    )
    (property "Footprint" "sa800u-baseboard-hw-footprints:TP_SMD_0.75mm" (id 2) (at 49.657 120.142 0)
      (effects (font (size 1.524 1.524)) (justify left) hide)
    )
    (property "Datasheet" "" (id 3) (at 52.197 120.142 0)
      (effects (font (size 1.524 1.524)) (justify left) hide)
    )
    (property "MPN" "" (id 4) (at 29.337 107.442 0)
      (effects (font (size 1.27 1.27) (thickness 0.15)) (justify left bottom) hide)
    )
    (property "Manufacturer" "" (id 5) (at 26.797 107.442 0)
      (effects (font (size 1.27 1.27) (thickness 0.15)) (justify left bottom) hide)
    )
    (property "Author" "Antmicro" (id 6) (at 24.257 107.442 0)
      (effects (font (size 1.27 1.27) (thickness 0.15)) (justify left bottom) hide)
    )
    (property "License" "Apache-2.0" (id 7) (at 21.717 107.442 0)
      (effects (font (size 1.27 1.27) (thickness 0.15)) (justify left bottom) hide)
    )
    (pin "1")
  )

  (symbol (lib_id "sa800u-baseboard-hw:TP_0.75mm_SMD") (at 245.491 124.46 90) (unit 1)
    (in_bom yes) (on_board yes) (fields_autoplaced)
    (property "Reference" "TP111" (id 0) (at 247.523 121.2849 90)
      (effects (font (size 1.27 1.27)) (justify right))
    )
    (property "Value" "TP_0.75mm_SMD" (id 1) (at 248.031 124.46 0)
      (effects (font (size 1.27 1.27)) hide)
    )
    (property "Footprint" "sa800u-baseboard-hw-footprints:TP_SMD_0.75mm" (id 2) (at 240.411 119.38 0)
      (effects (font (size 1.524 1.524)) (justify left) hide)
    )
    (property "Datasheet" "" (id 3) (at 237.871 119.38 0)
      (effects (font (size 1.524 1.524)) (justify left) hide)
    )
    (property "MPN" "" (id 4) (at 260.731 106.68 0)
      (effects (font (size 1.27 1.27) (thickness 0.15)) (justify left bottom) hide)
    )
    (property "Manufacturer" "" (id 5) (at 263.271 106.68 0)
      (effects (font (size 1.27 1.27) (thickness 0.15)) (justify left bottom) hide)
    )
    (property "Author" "Antmicro" (id 6) (at 265.811 106.68 0)
      (effects (font (size 1.27 1.27) (thickness 0.15)) (justify left bottom) hide)
    )
    (property "License" "Apache-2.0" (id 7) (at 268.351 106.68 0)
      (effects (font (size 1.27 1.27) (thickness 0.15)) (justify left bottom) hide)
    )
    (pin "1")
  )

  (symbol (lib_id "sa800u-baseboard-hw:PUSB3F96X_PASS") (at 283.845 149.225 270) (unit 1)
    (in_bom yes) (on_board yes) (fields_autoplaced)
    (property "Reference" "D11" (id 0) (at 288.29 155.575 90)
      (effects (font (size 1.524 1.524)) (justify left))
    )
    (property "Value" "PUSB3F96X_PASS" (id 1) (at 288.29 159.385 90)
      (effects (font (size 1.524 1.524)) (justify left))
    )
    (property "Footprint" "sa800u-baseboard-hw-footprints:Nexperia_DFN-10_2.5x1mm_P0.5mm" (id 2) (at 269.875 154.305 0)
      (effects (font (size 1.524 1.524)) hide)
    )
    (property "Datasheet" "https://pl.mouser.com/datasheet/2/916/PUSB3F96-1600324.pdf" (id 3) (at 283.845 149.225 0)
      (effects (font (size 1.524 1.524)) hide)
    )
    (property "Manufacturer" "Nexperia" (id 4) (at 267.335 154.305 0)
      (effects (font (size 1.27 1.27)) hide)
    )
    (property "MPN" "PUSB3F96X" (id 5) (at 267.335 154.305 0)
      (effects (font (size 1.27 1.27)) hide)
    )
    (property "Author" "Antmicro" (id 6) (at 266.065 174.625 0)
      (effects (font (size 1.27 1.27) (thickness 0.15)) (justify left bottom) hide)
    )
    (property "License" "Apache-2.0" (id 7) (at 263.525 174.625 0)
      (effects (font (size 1.27 1.27) (thickness 0.15)) (justify left bottom) hide)
    )
    (pin "1")
    (pin "10")
    (pin "2")
    (pin "3")
    (pin "4")
    (pin "5")
    (pin "6")
    (pin "7")
    (pin "8")
    (pin "9")
  )

  (symbol (lib_id "sa800u-baseboard-hw:PUSB3F96X_PASS") (at 194.945 77.47 270) (unit 1)
    (in_bom yes) (on_board yes) (fields_autoplaced)
    (property "Reference" "D8" (id 0) (at 189.865 93.98 90)
      (effects (font (size 1.524 1.524)))
    )
    (property "Value" "PUSB3F96X_PASS" (id 1) (at 189.865 97.79 90)
      (effects (font (size 1.524 1.524)))
    )
    (property "Footprint" "sa800u-baseboard-hw-footprints:Nexperia_DFN-10_2.5x1mm_P0.5mm" (id 2) (at 180.975 82.55 0)
      (effects (font (size 1.524 1.524)) hide)
    )
    (property "Datasheet" "https://pl.mouser.com/datasheet/2/916/PUSB3F96-1600324.pdf" (id 3) (at 194.945 77.47 0)
      (effects (font (size 1.524 1.524)) hide)
    )
    (property "Manufacturer" "Nexperia" (id 4) (at 178.435 82.55 0)
      (effects (font (size 1.27 1.27)) hide)
    )
    (property "MPN" "PUSB3F96X" (id 5) (at 178.435 82.55 0)
      (effects (font (size 1.27 1.27)) hide)
    )
    (property "Author" "Antmicro" (id 6) (at 177.165 102.87 0)
      (effects (font (size 1.27 1.27) (thickness 0.15)) (justify left bottom) hide)
    )
    (property "License" "Apache-2.0" (id 7) (at 174.625 102.87 0)
      (effects (font (size 1.27 1.27) (thickness 0.15)) (justify left bottom) hide)
    )
    (pin "1")
    (pin "10")
    (pin "2")
    (pin "3")
    (pin "4")
    (pin "5")
    (pin "6")
    (pin "7")
    (pin "8")
    (pin "9")
  )

  (symbol (lib_id "sa800u-baseboard-hw:TP_0.75mm_SMD") (at 93.472 122.555 90) (unit 1)
    (in_bom yes) (on_board yes) (fields_autoplaced)
    (property "Reference" "TP101" (id 0) (at 93.472 115.824 90))
    (property "Value" "TP_0.75mm_SMD" (id 1) (at 96.012 122.555 0)
      (effects (font (size 1.27 1.27)) hide)
    )
    (property "Footprint" "sa800u-baseboard-hw-footprints:TP_SMD_0.75mm" (id 2) (at 88.392 117.475 0)
      (effects (font (size 1.524 1.524)) (justify left) hide)
    )
    (property "Datasheet" "" (id 3) (at 85.852 117.475 0)
      (effects (font (size 1.524 1.524)) (justify left) hide)
    )
    (property "MPN" "" (id 4) (at 108.712 104.775 0)
      (effects (font (size 1.27 1.27) (thickness 0.15)) (justify left bottom) hide)
    )
    (property "Manufacturer" "" (id 5) (at 111.252 104.775 0)
      (effects (font (size 1.27 1.27) (thickness 0.15)) (justify left bottom) hide)
    )
    (property "Author" "Antmicro" (id 6) (at 113.792 104.775 0)
      (effects (font (size 1.27 1.27) (thickness 0.15)) (justify left bottom) hide)
    )
    (property "License" "Apache-2.0" (id 7) (at 116.332 104.775 0)
      (effects (font (size 1.27 1.27) (thickness 0.15)) (justify left bottom) hide)
    )
    (pin "1")
  )

  (symbol (lib_id "sa800u-baseboard-hw:PUSB3F96X_PASS") (at 167.64 77.47 270) (unit 1)
    (in_bom yes) (on_board yes) (fields_autoplaced)
    (property "Reference" "D7" (id 0) (at 162.56 93.98 90)
      (effects (font (size 1.524 1.524)))
    )
    (property "Value" "PUSB3F96X_PASS" (id 1) (at 162.56 97.79 90)
      (effects (font (size 1.524 1.524)))
    )
    (property "Footprint" "sa800u-baseboard-hw-footprints:Nexperia_DFN-10_2.5x1mm_P0.5mm" (id 2) (at 153.67 82.55 0)
      (effects (font (size 1.524 1.524)) hide)
    )
    (property "Datasheet" "https://pl.mouser.com/datasheet/2/916/PUSB3F96-1600324.pdf" (id 3) (at 167.64 77.47 0)
      (effects (font (size 1.524 1.524)) hide)
    )
    (property "Manufacturer" "Nexperia" (id 4) (at 151.13 82.55 0)
      (effects (font (size 1.27 1.27)) hide)
    )
    (property "MPN" "PUSB3F96X" (id 5) (at 151.13 82.55 0)
      (effects (font (size 1.27 1.27)) hide)
    )
    (property "Author" "Antmicro" (id 6) (at 149.86 102.87 0)
      (effects (font (size 1.27 1.27) (thickness 0.15)) (justify left bottom) hide)
    )
    (property "License" "Apache-2.0" (id 7) (at 147.32 102.87 0)
      (effects (font (size 1.27 1.27) (thickness 0.15)) (justify left bottom) hide)
    )
    (pin "1")
    (pin "10")
    (pin "2")
    (pin "3")
    (pin "4")
    (pin "5")
    (pin "6")
    (pin "7")
    (pin "8")
    (pin "9")
  )

  (symbol (lib_id "sa800u-baseboard-hw:TP_0.75mm_SMD") (at 107.95 62.865 90) (unit 1)
    (in_bom yes) (on_board yes)
    (property "Reference" "TP103" (id 0) (at 107.95 57.531 90))
    (property "Value" "TP_0.75mm_SMD" (id 1) (at 110.49 62.865 0)
      (effects (font (size 1.27 1.27)) hide)
    )
    (property "Footprint" "sa800u-baseboard-hw-footprints:TP_SMD_0.75mm" (id 2) (at 102.87 57.785 0)
      (effects (font (size 1.524 1.524)) (justify left) hide)
    )
    (property "Datasheet" "" (id 3) (at 100.33 57.785 0)
      (effects (font (size 1.524 1.524)) (justify left) hide)
    )
    (property "MPN" "" (id 4) (at 123.19 45.085 0)
      (effects (font (size 1.27 1.27) (thickness 0.15)) (justify left bottom) hide)
    )
    (property "Manufacturer" "" (id 5) (at 125.73 45.085 0)
      (effects (font (size 1.27 1.27) (thickness 0.15)) (justify left bottom) hide)
    )
    (property "Author" "Antmicro" (id 6) (at 128.27 45.085 0)
      (effects (font (size 1.27 1.27) (thickness 0.15)) (justify left bottom) hide)
    )
    (property "License" "Apache-2.0" (id 7) (at 130.81 45.085 0)
      (effects (font (size 1.27 1.27) (thickness 0.15)) (justify left bottom) hide)
    )
    (pin "1")
  )

  (symbol (lib_id "sa800u-baseboard-hw:C_100n_0402") (at 288.29 82.55 0) (unit 1)
    (in_bom yes) (on_board yes)
    (property "Reference" "C84" (id 0) (at 285.369 81.407 0)
      (effects (font (size 1.524 1.524)))
    )
    (property "Value" "C_100n_0402" (id 1) (at 288.29 86.36 0)
      (effects (font (size 1.524 1.524)) hide)
    )
    (property "Footprint" "sa800u-baseboard-hw-footprints:C_0402_1005Metric" (id 2) (at 293.37 77.47 0)
      (effects (font (size 1.524 1.524)) (justify left) hide)
    )
    (property "Datasheet" "https://search.murata.co.jp/Ceramy/image/img/A01X/G101/ENG/GRM155R61H104KE14-01.pdf" (id 3) (at 288.29 82.55 0)
      (effects (font (size 1.27 1.27)) hide)
    )
    (property "Manufacturer" "Murata" (id 4) (at 293.37 72.39 0)
      (effects (font (size 1.524 1.524)) (justify left) hide)
    )
    (property "MPN" "GRM155R61H104KE14D" (id 5) (at 293.37 74.93 0)
      (effects (font (size 1.524 1.524)) (justify left) hide)
    )
    (property "Val" "100n" (id 6) (at 294.005 81.407 0))
    (property "License" "Apache-2.0" (id 7) (at 308.61 105.41 0)
      (effects (font (size 1.27 1.27) (thickness 0.15)) (justify left bottom) hide)
    )
    (property "Author" "Antmicro" (id 8) (at 308.61 107.95 0)
      (effects (font (size 1.27 1.27) (thickness 0.15)) (justify left bottom) hide)
    )
    (property "Voltage" "50V" (id 9) (at 308.61 110.49 0)
      (effects (font (size 1.27 1.27)) (justify left bottom) hide)
    )
    (property "Dielectric" "X5R" (id 10) (at 308.61 113.03 0)
      (effects (font (size 1.27 1.27)) (justify left bottom) hide)
    )
    (pin "1")
    (pin "2")
  )

  (symbol (lib_id "sa800u-baseboard-hw:C_100n_0402") (at 285.75 85.09 0) (unit 1)
    (in_bom yes) (on_board yes)
    (property "Reference" "C80" (id 0) (at 285.369 84.074 0)
      (effects (font (size 1.524 1.524)))
    )
    (property "Value" "C_100n_0402" (id 1) (at 285.75 88.9 0)
      (effects (font (size 1.524 1.524)) hide)
    )
    (property "Footprint" "sa800u-baseboard-hw-footprints:C_0402_1005Metric" (id 2) (at 290.83 80.01 0)
      (effects (font (size 1.524 1.524)) (justify left) hide)
    )
    (property "Datasheet" "https://search.murata.co.jp/Ceramy/image/img/A01X/G101/ENG/GRM155R61H104KE14-01.pdf" (id 3) (at 285.75 85.09 0)
      (effects (font (size 1.27 1.27)) hide)
    )
    (property "Manufacturer" "Murata" (id 4) (at 290.83 74.93 0)
      (effects (font (size 1.524 1.524)) (justify left) hide)
    )
    (property "MPN" "GRM155R61H104KE14D" (id 5) (at 290.83 77.47 0)
      (effects (font (size 1.524 1.524)) (justify left) hide)
    )
    (property "Val" "100n" (id 6) (at 294.132 84.074 0))
    (property "License" "Apache-2.0" (id 7) (at 306.07 107.95 0)
      (effects (font (size 1.27 1.27) (thickness 0.15)) (justify left bottom) hide)
    )
    (property "Author" "Antmicro" (id 8) (at 306.07 110.49 0)
      (effects (font (size 1.27 1.27) (thickness 0.15)) (justify left bottom) hide)
    )
    (property "Voltage" "50V" (id 9) (at 306.07 113.03 0)
      (effects (font (size 1.27 1.27)) (justify left bottom) hide)
    )
    (property "Dielectric" "X5R" (id 10) (at 306.07 115.57 0)
      (effects (font (size 1.27 1.27)) (justify left bottom) hide)
    )
    (pin "1")
    (pin "2")
  )

  (symbol (lib_id "sa800u-baseboard-hw:TPS7A0518P_SOT23-5") (at 236.728 125.73 0) (mirror y) (unit 1)
    (in_bom yes) (on_board yes) (fields_autoplaced)
    (property "Reference" "IC1" (id 0) (at 229.108 118.11 0))
    (property "Value" "TPS7A0518P_SOT23-5" (id 1) (at 229.108 115.57 0)
      (effects (font (size 0.9906 0.9906)) hide)
    )
    (property "Footprint" "sa800u-baseboard-hw-footprints:SOT-23-5" (id 2) (at 236.728 132.08 0)
      (effects (font (size 1.27 1.27)) hide)
    )
    (property "Datasheet" "https://www.ti.com/lit/ds/symlink/tps7a05.pdf?ts=1678973651768&ref_url=https%253A%252F%252Fwww.google.com%252F" (id 3) (at 236.728 125.73 0)
      (effects (font (size 1.27 1.27)) hide)
    )
    (property "MPN" "TPS7A0518PDBVT" (id 4) (at 229.108 120.65 0))
    (property "Manufacturer" "Texas Instruments" (id 5) (at 229.108 120.65 0)
      (effects (font (size 1.27 1.27)) hide)
    )
    (property "Author" "Antmicro" (id 6) (at 210.058 142.24 0)
      (effects (font (size 1.27 1.27) (thickness 0.15)) (justify left bottom) hide)
    )
    (property "License" "Apache-2.0" (id 7) (at 210.058 144.78 0)
      (effects (font (size 1.27 1.27) (thickness 0.15)) (justify left bottom) hide)
    )
    (pin "1")
    (pin "2")
    (pin "3")
    (pin "4")
    (pin "5")
  )

  (symbol (lib_id "sa800u-baseboard-hw:GND") (at 266.065 152.4 0) (unit 1)
    (in_bom yes) (on_board yes) (fields_autoplaced)
    (property "Reference" "#PWR068" (id 0) (at 266.065 158.75 0)
      (effects (font (size 1.27 1.27)) hide)
    )
    (property "Value" "GND" (id 1) (at 264.16 153.6699 0)
      (effects (font (size 1.27 1.27)) (justify right))
    )
    (property "Footprint" "" (id 2) (at 266.065 152.4 0)
      (effects (font (size 1.27 1.27)) hide)
    )
    (property "Datasheet" "" (id 3) (at 266.065 152.4 0)
      (effects (font (size 1.27 1.27)) hide)
    )
    (property "Author" "Antmicro" (id 4) (at 274.955 160.02 0)
      (effects (font (size 1.27 1.27) (thickness 0.15)) (justify left bottom) hide)
    )
    (property "License" "Apache-2.0" (id 5) (at 274.955 162.56 0)
      (effects (font (size 1.27 1.27) (thickness 0.15)) (justify left bottom) hide)
    )
    (pin "1")
  )

  (symbol (lib_id "sa800u-baseboard-hw:C_100n_0402") (at 60.325 238.76 270) (unit 1)
    (in_bom yes) (on_board yes) (fields_autoplaced)
    (property "Reference" "C63" (id 0) (at 57.023 240.0363 90)
      (effects (font (size 1.524 1.524)) (justify right))
    )
    (property "Value" "C_100n_0402" (id 1) (at 56.515 238.76 0)
      (effects (font (size 1.524 1.524)) hide)
    )
    (property "Footprint" "sa800u-baseboard-hw-footprints:C_0402_1005Metric" (id 2) (at 65.405 243.84 0)
      (effects (font (size 1.524 1.524)) (justify left) hide)
    )
    (property "Datasheet" "https://search.murata.co.jp/Ceramy/image/img/A01X/G101/ENG/GRM155R61H104KE14-01.pdf" (id 3) (at 60.325 238.76 0)
      (effects (font (size 1.27 1.27)) hide)
    )
    (property "Manufacturer" "Murata" (id 4) (at 70.485 243.84 0)
      (effects (font (size 1.524 1.524)) (justify left) hide)
    )
    (property "MPN" "GRM155R61H104KE14D" (id 5) (at 67.945 243.84 0)
      (effects (font (size 1.524 1.524)) (justify left) hide)
    )
    (property "Val" "100n" (id 6) (at 57.023 243.2112 90)
      (effects (font (size 1.27 1.27)) (justify right))
    )
    (property "License" "Apache-2.0" (id 7) (at 37.465 259.08 0)
      (effects (font (size 1.27 1.27) (thickness 0.15)) (justify left bottom) hide)
    )
    (property "Author" "Antmicro" (id 8) (at 34.925 259.08 0)
      (effects (font (size 1.27 1.27) (thickness 0.15)) (justify left bottom) hide)
    )
    (property "Voltage" "50V" (id 9) (at 32.385 259.08 0)
      (effects (font (size 1.27 1.27)) (justify left bottom) hide)
    )
    (property "Dielectric" "X5R" (id 10) (at 29.845 259.08 0)
      (effects (font (size 1.27 1.27)) (justify left bottom) hide)
    )
    (pin "1")
    (pin "2")
  )

  (symbol (lib_id "sa800u-baseboard-hw:C_100n_0402") (at 65.405 238.76 270) (unit 1)
    (in_bom yes) (on_board yes) (fields_autoplaced)
    (property "Reference" "C65" (id 0) (at 68.707 240.0363 90)
      (effects (font (size 1.524 1.524)) (justify left))
    )
    (property "Value" "C_100n_0402" (id 1) (at 61.595 238.76 0)
      (effects (font (size 1.524 1.524)) hide)
    )
    (property "Footprint" "sa800u-baseboard-hw-footprints:C_0402_1005Metric" (id 2) (at 70.485 243.84 0)
      (effects (font (size 1.524 1.524)) (justify left) hide)
    )
    (property "Datasheet" "https://search.murata.co.jp/Ceramy/image/img/A01X/G101/ENG/GRM155R61H104KE14-01.pdf" (id 3) (at 65.405 238.76 0)
      (effects (font (size 1.27 1.27)) hide)
    )
    (property "Manufacturer" "Murata" (id 4) (at 75.565 243.84 0)
      (effects (font (size 1.524 1.524)) (justify left) hide)
    )
    (property "MPN" "GRM155R61H104KE14D" (id 5) (at 73.025 243.84 0)
      (effects (font (size 1.524 1.524)) (justify left) hide)
    )
    (property "Val" "100n" (id 6) (at 68.707 243.2112 90)
      (effects (font (size 1.27 1.27)) (justify left))
    )
    (property "License" "Apache-2.0" (id 7) (at 42.545 259.08 0)
      (effects (font (size 1.27 1.27) (thickness 0.15)) (justify left bottom) hide)
    )
    (property "Author" "Antmicro" (id 8) (at 40.005 259.08 0)
      (effects (font (size 1.27 1.27) (thickness 0.15)) (justify left bottom) hide)
    )
    (property "Voltage" "50V" (id 9) (at 37.465 259.08 0)
      (effects (font (size 1.27 1.27)) (justify left bottom) hide)
    )
    (property "Dielectric" "X5R" (id 10) (at 34.925 259.08 0)
      (effects (font (size 1.27 1.27)) (justify left bottom) hide)
    )
    (pin "1")
    (pin "2")
  )

  (symbol (lib_id "sa800u-baseboard-hw:GND") (at 65.405 243.84 0) (unit 1)
    (in_bom yes) (on_board yes) (fields_autoplaced)
    (property "Reference" "#PWR046" (id 0) (at 65.405 250.19 0)
      (effects (font (size 1.27 1.27)) hide)
    )
    (property "Value" "GND" (id 1) (at 65.405 248.92 0))
    (property "Footprint" "" (id 2) (at 65.405 243.84 0)
      (effects (font (size 1.27 1.27)) hide)
    )
    (property "Datasheet" "" (id 3) (at 65.405 243.84 0)
      (effects (font (size 1.27 1.27)) hide)
    )
    (property "Author" "Antmicro" (id 4) (at 74.295 251.46 0)
      (effects (font (size 1.27 1.27) (thickness 0.15)) (justify left bottom) hide)
    )
    (property "License" "Apache-2.0" (id 5) (at 74.295 254 0)
      (effects (font (size 1.27 1.27) (thickness 0.15)) (justify left bottom) hide)
    )
    (pin "1")
  )

  (symbol (lib_id "sa800u-baseboard-hw:GND") (at 60.325 243.84 0) (unit 1)
    (in_bom yes) (on_board yes) (fields_autoplaced)
    (property "Reference" "#PWR043" (id 0) (at 60.325 250.19 0)
      (effects (font (size 1.27 1.27)) hide)
    )
    (property "Value" "GND" (id 1) (at 60.325 248.92 0))
    (property "Footprint" "" (id 2) (at 60.325 243.84 0)
      (effects (font (size 1.27 1.27)) hide)
    )
    (property "Datasheet" "" (id 3) (at 60.325 243.84 0)
      (effects (font (size 1.27 1.27)) hide)
    )
    (property "Author" "Antmicro" (id 4) (at 69.215 251.46 0)
      (effects (font (size 1.27 1.27) (thickness 0.15)) (justify left bottom) hide)
    )
    (property "License" "Apache-2.0" (id 5) (at 69.215 254 0)
      (effects (font (size 1.27 1.27) (thickness 0.15)) (justify left bottom) hide)
    )
    (pin "1")
  )

  (symbol (lib_id "sa800u-baseboard-hw:TP_0.75mm_SMD") (at 111.76 62.865 90) (unit 1)
    (in_bom yes) (on_board yes)
    (property "Reference" "TP104" (id 0) (at 113.157 59.817 90)
      (effects (font (size 1.27 1.27)) (justify right))
    )
    (property "Value" "TP_0.75mm_SMD" (id 1) (at 114.3 62.865 0)
      (effects (font (size 1.27 1.27)) hide)
    )
    (property "Footprint" "sa800u-baseboard-hw-footprints:TP_SMD_0.75mm" (id 2) (at 106.68 57.785 0)
      (effects (font (size 1.524 1.524)) (justify left) hide)
    )
    (property "Datasheet" "" (id 3) (at 104.14 57.785 0)
      (effects (font (size 1.524 1.524)) (justify left) hide)
    )
    (property "MPN" "" (id 4) (at 127 45.085 0)
      (effects (font (size 1.27 1.27) (thickness 0.15)) (justify left bottom) hide)
    )
    (property "Manufacturer" "" (id 5) (at 129.54 45.085 0)
      (effects (font (size 1.27 1.27) (thickness 0.15)) (justify left bottom) hide)
    )
    (property "Author" "Antmicro" (id 6) (at 132.08 45.085 0)
      (effects (font (size 1.27 1.27) (thickness 0.15)) (justify left bottom) hide)
    )
    (property "License" "Apache-2.0" (id 7) (at 134.62 45.085 0)
      (effects (font (size 1.27 1.27) (thickness 0.15)) (justify left bottom) hide)
    )
    (pin "1")
  )

  (symbol (lib_id "sa800u-baseboard-hw:GND") (at 336.423 99.06 0) (unit 1)
    (in_bom yes) (on_board yes) (fields_autoplaced)
    (property "Reference" "#PWR074" (id 0) (at 336.423 105.41 0)
      (effects (font (size 1.27 1.27)) hide)
    )
    (property "Value" "GND" (id 1) (at 336.423 104.14 0))
    (property "Footprint" "" (id 2) (at 336.423 99.06 0)
      (effects (font (size 1.27 1.27)) hide)
    )
    (property "Datasheet" "" (id 3) (at 336.423 99.06 0)
      (effects (font (size 1.27 1.27)) hide)
    )
    (property "Author" "Antmicro" (id 4) (at 345.313 106.68 0)
      (effects (font (size 1.27 1.27) (thickness 0.15)) (justify left bottom) hide)
    )
    (property "License" "Apache-2.0" (id 5) (at 345.313 109.22 0)
      (effects (font (size 1.27 1.27) (thickness 0.15)) (justify left bottom) hide)
    )
    (pin "1")
  )

  (symbol (lib_id "sa800u-baseboard-hw:FB_220Z_1A_0603") (at 277.876 125.73 0) (mirror y) (unit 1)
    (in_bom yes) (on_board yes) (fields_autoplaced)
    (property "Reference" "FB3" (id 0) (at 275.3741 130.81 0)
      (effects (font (size 1.524 1.524)))
    )
    (property "Value" "FB_220Z_1A_0603" (id 1) (at 262.636 133.35 0)
      (effects (font (size 1.27 1.27) (thickness 0.15)) (justify left bottom) hide)
    )
    (property "Footprint" "sa800u-baseboard-hw-footprints:FB_0603_1608Metric" (id 2) (at 262.636 135.89 0)
      (effects (font (size 1.27 1.27) (thickness 0.15)) (justify left bottom) hide)
    )
    (property "Datasheet" "https://www.murata.com/en-global/api/pdfdownloadapi?cate=luNoiseSupprFilteChipFerriBead&partno=BLM18EG221SN1%23" (id 3) (at 262.636 138.43 0)
      (effects (font (size 1.27 1.27) (thickness 0.15)) (justify left bottom) hide)
    )
    (property "MPN" "BLM18EG221SN1D" (id 4) (at 275.3741 133.35 0)
      (effects (font (size 1.27 1.27) (thickness 0.15)))
    )
    (property "Manufacturer" "Murata" (id 5) (at 262.636 143.51 0)
      (effects (font (size 1.27 1.27) (thickness 0.15)) (justify left bottom) hide)
    )
    (property "Author" "Antmicro" (id 6) (at 262.636 146.05 0)
      (effects (font (size 1.27 1.27) (thickness 0.15)) (justify left bottom) hide)
    )
    (property "License" "Apache-2.0" (id 7) (at 262.636 148.59 0)
      (effects (font (size 1.27 1.27) (thickness 0.15)) (justify left bottom) hide)
    )
    (pin "1")
    (pin "2")
  )

  (symbol (lib_id "sa800u-baseboard-hw:TP_0.75mm_SMD") (at 134.62 203.2 0) (unit 1)
    (in_bom yes) (on_board yes) (fields_autoplaced)
    (property "Reference" "TP108" (id 0) (at 139.192 203.1999 0)
      (effects (font (size 1.27 1.27)) (justify left))
    )
    (property "Value" "TP_0.75mm_SMD" (id 1) (at 134.62 205.74 0)
      (effects (font (size 1.27 1.27)) hide)
    )
    (property "Footprint" "sa800u-baseboard-hw-footprints:TP_SMD_0.75mm" (id 2) (at 139.7 198.12 0)
      (effects (font (size 1.524 1.524)) (justify left) hide)
    )
    (property "Datasheet" "" (id 3) (at 139.7 195.58 0)
      (effects (font (size 1.524 1.524)) (justify left) hide)
    )
    (property "MPN" "" (id 4) (at 152.4 218.44 0)
      (effects (font (size 1.27 1.27) (thickness 0.15)) (justify left bottom) hide)
    )
    (property "Manufacturer" "" (id 5) (at 152.4 220.98 0)
      (effects (font (size 1.27 1.27) (thickness 0.15)) (justify left bottom) hide)
    )
    (property "Author" "Antmicro" (id 6) (at 152.4 223.52 0)
      (effects (font (size 1.27 1.27) (thickness 0.15)) (justify left bottom) hide)
    )
    (property "License" "Apache-2.0" (id 7) (at 152.4 226.06 0)
      (effects (font (size 1.27 1.27) (thickness 0.15)) (justify left bottom) hide)
    )
    (pin "1")
  )

  (symbol (lib_id "sa800u-baseboard-hw:TP_0.75mm_SMD") (at 134.62 207.01 0) (unit 1)
    (in_bom yes) (on_board yes) (fields_autoplaced)
    (property "Reference" "TP109" (id 0) (at 139.827 207.0099 0)
      (effects (font (size 1.27 1.27)) (justify left))
    )
    (property "Value" "TP_0.75mm_SMD" (id 1) (at 134.62 209.55 0)
      (effects (font (size 1.27 1.27)) hide)
    )
    (property "Footprint" "sa800u-baseboard-hw-footprints:TP_SMD_0.75mm" (id 2) (at 139.7 201.93 0)
      (effects (font (size 1.524 1.524)) (justify left) hide)
    )
    (property "Datasheet" "" (id 3) (at 139.7 199.39 0)
      (effects (font (size 1.524 1.524)) (justify left) hide)
    )
    (property "MPN" "" (id 4) (at 152.4 222.25 0)
      (effects (font (size 1.27 1.27) (thickness 0.15)) (justify left bottom) hide)
    )
    (property "Manufacturer" "" (id 5) (at 152.4 224.79 0)
      (effects (font (size 1.27 1.27) (thickness 0.15)) (justify left bottom) hide)
    )
    (property "Author" "Antmicro" (id 6) (at 152.4 227.33 0)
      (effects (font (size 1.27 1.27) (thickness 0.15)) (justify left bottom) hide)
    )
    (property "License" "Apache-2.0" (id 7) (at 152.4 229.87 0)
      (effects (font (size 1.27 1.27) (thickness 0.15)) (justify left bottom) hide)
    )
    (pin "1")
  )

  (symbol (lib_id "sa800u-baseboard-hw:GND") (at 337.058 244.475 0) (unit 1)
    (in_bom yes) (on_board yes) (fields_autoplaced)
    (property "Reference" "#PWR075" (id 0) (at 337.058 250.825 0)
      (effects (font (size 1.27 1.27)) hide)
    )
    (property "Value" "GND" (id 1) (at 337.058 248.92 0))
    (property "Footprint" "" (id 2) (at 337.058 244.475 0)
      (effects (font (size 1.27 1.27)) hide)
    )
    (property "Datasheet" "" (id 3) (at 337.058 244.475 0)
      (effects (font (size 1.27 1.27)) hide)
    )
    (property "Author" "Antmicro" (id 4) (at 345.948 252.095 0)
      (effects (font (size 1.27 1.27) (thickness 0.15)) (justify left bottom) hide)
    )
    (property "License" "Apache-2.0" (id 5) (at 345.948 254.635 0)
      (effects (font (size 1.27 1.27) (thickness 0.15)) (justify left bottom) hide)
    )
    (pin "1")
  )

  (symbol (lib_id "sa800u-baseboard-hw:C_2u2_0603") (at 247.015 127.635 90) (mirror x) (unit 1)
    (in_bom yes) (on_board yes) (fields_autoplaced)
    (property "Reference" "C77" (id 0) (at 250.063 128.9113 90)
      (effects (font (size 1.524 1.524)) (justify right))
    )
    (property "Value" "C_2u2_0603" (id 1) (at 250.825 127.635 0)
      (effects (font (size 1.524 1.524)) hide)
    )
    (property "Footprint" "sa800u-baseboard-hw-footprints:C_0603_1608Metric" (id 2) (at 241.935 132.715 0)
      (effects (font (size 1.524 1.524)) (justify left) hide)
    )
    (property "Datasheet" " " (id 3) (at 247.015 127.635 0)
      (effects (font (size 1.27 1.27)) hide)
    )
    (property "Manufacturer" "TDK" (id 4) (at 236.855 132.715 0)
      (effects (font (size 1.524 1.524)) (justify left) hide)
    )
    (property "MPN" "C1608X5R1V225K080AC" (id 5) (at 239.395 132.715 0)
      (effects (font (size 1.524 1.524)) (justify left) hide)
    )
    (property "Val" "2u2" (id 6) (at 250.063 132.0862 90)
      (effects (font (size 1.27 1.27)) (justify right))
    )
    (property "License" "Apache-2.0" (id 7) (at 269.875 147.955 0)
      (effects (font (size 1.27 1.27) (thickness 0.15)) (justify left bottom) hide)
    )
    (property "Author" "Antmicro" (id 8) (at 272.415 147.955 0)
      (effects (font (size 1.27 1.27) (thickness 0.15)) (justify left bottom) hide)
    )
    (property "Voltage" "" (id 9) (at 274.955 147.955 0)
      (effects (font (size 1.27 1.27)) (justify left bottom) hide)
    )
    (property "Dielectric" "" (id 10) (at 277.495 147.955 0)
      (effects (font (size 1.27 1.27)) (justify left bottom) hide)
    )
    (pin "1")
    (pin "2")
  )

  (symbol (lib_id "sa800u-baseboard-hw:TP_0.75mm_SMD") (at 134.62 210.82 0) (unit 1)
    (in_bom yes) (on_board yes) (fields_autoplaced)
    (property "Reference" "TP110" (id 0) (at 139.954 210.8199 0)
      (effects (font (size 1.27 1.27)) (justify left))
    )
    (property "Value" "TP_0.75mm_SMD" (id 1) (at 134.62 213.36 0)
      (effects (font (size 1.27 1.27)) hide)
    )
    (property "Footprint" "sa800u-baseboard-hw-footprints:TP_SMD_0.75mm" (id 2) (at 139.7 205.74 0)
      (effects (font (size 1.524 1.524)) (justify left) hide)
    )
    (property "Datasheet" "" (id 3) (at 139.7 203.2 0)
      (effects (font (size 1.524 1.524)) (justify left) hide)
    )
    (property "MPN" "" (id 4) (at 152.4 226.06 0)
      (effects (font (size 1.27 1.27) (thickness 0.15)) (justify left bottom) hide)
    )
    (property "Manufacturer" "" (id 5) (at 152.4 228.6 0)
      (effects (font (size 1.27 1.27) (thickness 0.15)) (justify left bottom) hide)
    )
    (property "Author" "Antmicro" (id 6) (at 152.4 231.14 0)
      (effects (font (size 1.27 1.27) (thickness 0.15)) (justify left bottom) hide)
    )
    (property "License" "Apache-2.0" (id 7) (at 152.4 233.68 0)
      (effects (font (size 1.27 1.27) (thickness 0.15)) (justify left bottom) hide)
    )
    (pin "1")
  )

  (symbol (lib_id "sa800u-baseboard-hw:GND") (at 247.015 132.715 0) (mirror y) (unit 1)
    (in_bom yes) (on_board yes) (fields_autoplaced)
    (property "Reference" "#PWR066" (id 0) (at 247.015 139.065 0)
      (effects (font (size 1.27 1.27)) hide)
    )
    (property "Value" "GND" (id 1) (at 247.015 137.16 0))
    (property "Footprint" "" (id 2) (at 247.015 132.715 0)
      (effects (font (size 1.27 1.27)) hide)
    )
    (property "Datasheet" "" (id 3) (at 247.015 132.715 0)
      (effects (font (size 1.27 1.27)) hide)
    )
    (property "Author" "Antmicro" (id 4) (at 238.125 140.335 0)
      (effects (font (size 1.27 1.27) (thickness 0.15)) (justify left bottom) hide)
    )
    (property "License" "Apache-2.0" (id 5) (at 238.125 142.875 0)
      (effects (font (size 1.27 1.27) (thickness 0.15)) (justify left bottom) hide)
    )
    (pin "1")
  )

  (symbol (lib_id "sa800u-baseboard-hw:GND") (at 219.075 129.54 0) (mirror y) (unit 1)
    (in_bom yes) (on_board yes) (fields_autoplaced)
    (property "Reference" "#PWR064" (id 0) (at 219.075 135.89 0)
      (effects (font (size 1.27 1.27)) hide)
    )
    (property "Value" "GND" (id 1) (at 219.075 134.62 0))
    (property "Footprint" "" (id 2) (at 219.075 129.54 0)
      (effects (font (size 1.27 1.27)) hide)
    )
    (property "Datasheet" "" (id 3) (at 219.075 129.54 0)
      (effects (font (size 1.27 1.27)) hide)
    )
    (property "Author" "Antmicro" (id 4) (at 210.185 137.16 0)
      (effects (font (size 1.27 1.27) (thickness 0.15)) (justify left bottom) hide)
    )
    (property "License" "Apache-2.0" (id 5) (at 210.185 139.7 0)
      (effects (font (size 1.27 1.27) (thickness 0.15)) (justify left bottom) hide)
    )
    (pin "1")
  )

  (symbol (lib_id "sa800u-baseboard-hw:GND") (at 337.693 170.18 0) (unit 1)
    (in_bom yes) (on_board yes) (fields_autoplaced)
    (property "Reference" "#PWR076" (id 0) (at 337.693 176.53 0)
      (effects (font (size 1.27 1.27)) hide)
    )
    (property "Value" "GND" (id 1) (at 337.693 175.26 0))
    (property "Footprint" "" (id 2) (at 337.693 170.18 0)
      (effects (font (size 1.27 1.27)) hide)
    )
    (property "Datasheet" "" (id 3) (at 337.693 170.18 0)
      (effects (font (size 1.27 1.27)) hide)
    )
    (property "Author" "Antmicro" (id 4) (at 346.583 177.8 0)
      (effects (font (size 1.27 1.27) (thickness 0.15)) (justify left bottom) hide)
    )
    (property "License" "Apache-2.0" (id 5) (at 346.583 180.34 0)
      (effects (font (size 1.27 1.27) (thickness 0.15)) (justify left bottom) hide)
    )
    (pin "1")
  )

  (symbol (lib_id "sa800u-baseboard-hw:C_1u_0603") (at 212.725 127.635 90) (mirror x) (unit 1)
    (in_bom yes) (on_board yes) (fields_autoplaced)
    (property "Reference" "C75" (id 0) (at 209.423 128.9113 90)
      (effects (font (size 1.524 1.524)) (justify left))
    )
    (property "Value" "C_1u_0603" (id 1) (at 216.535 127.635 0)
      (effects (font (size 1.524 1.524)) hide)
    )
    (property "Footprint" "sa800u-baseboard-hw-footprints:C_0603_1608Metric" (id 2) (at 207.645 132.715 0)
      (effects (font (size 1.524 1.524)) (justify left) hide)
    )
    (property "Datasheet" " " (id 3) (at 212.725 127.635 0)
      (effects (font (size 1.27 1.27)) hide)
    )
    (property "Manufacturer" "Walsin" (id 4) (at 202.565 132.715 0)
      (effects (font (size 1.524 1.524)) (justify left) hide)
    )
    (property "MPN" "0603YD105KAT2A" (id 5) (at 205.105 132.715 0)
      (effects (font (size 1.524 1.524)) (justify left) hide)
    )
    (property "Val" "1u" (id 6) (at 209.423 132.0862 90)
      (effects (font (size 1.27 1.27)) (justify left))
    )
    (property "License" "Apache-2.0" (id 7) (at 235.585 147.955 0)
      (effects (font (size 1.27 1.27) (thickness 0.15)) (justify left bottom) hide)
    )
    (property "Author" "Antmicro" (id 8) (at 238.125 147.955 0)
      (effects (font (size 1.27 1.27) (thickness 0.15)) (justify left bottom) hide)
    )
    (property "Voltage" "" (id 9) (at 240.665 147.955 0)
      (effects (font (size 1.27 1.27)) (justify left bottom) hide)
    )
    (property "Dielectric" "" (id 10) (at 243.205 147.955 0)
      (effects (font (size 1.27 1.27)) (justify left bottom) hide)
    )
    (pin "1")
    (pin "2")
  )

  (symbol (lib_id "sa800u-baseboard-hw:GND") (at 212.725 132.715 0) (mirror y) (unit 1)
    (in_bom yes) (on_board yes) (fields_autoplaced)
    (property "Reference" "#PWR063" (id 0) (at 212.725 139.065 0)
      (effects (font (size 1.27 1.27)) hide)
    )
    (property "Value" "GND" (id 1) (at 212.725 137.16 0))
    (property "Footprint" "" (id 2) (at 212.725 132.715 0)
      (effects (font (size 1.27 1.27)) hide)
    )
    (property "Datasheet" "" (id 3) (at 212.725 132.715 0)
      (effects (font (size 1.27 1.27)) hide)
    )
    (property "Author" "Antmicro" (id 4) (at 203.835 140.335 0)
      (effects (font (size 1.27 1.27) (thickness 0.15)) (justify left bottom) hide)
    )
    (property "License" "Apache-2.0" (id 5) (at 203.835 142.875 0)
      (effects (font (size 1.27 1.27) (thickness 0.15)) (justify left bottom) hide)
    )
    (pin "1")
  )

  (symbol (lib_id "sa800u-baseboard-hw:TP_0.75mm_SMD") (at 76.2 259.715 180) (unit 1)
    (in_bom yes) (on_board yes)
    (property "Reference" "TP102" (id 0) (at 68.58 259.715 0))
    (property "Value" "TP_0.75mm_SMD" (id 1) (at 76.2 257.175 0)
      (effects (font (size 1.27 1.27)) hide)
    )
    (property "Footprint" "sa800u-baseboard-hw-footprints:TP_SMD_0.75mm" (id 2) (at 71.12 264.795 0)
      (effects (font (size 1.524 1.524)) (justify left) hide)
    )
    (property "Datasheet" "" (id 3) (at 71.12 267.335 0)
      (effects (font (size 1.524 1.524)) (justify left) hide)
    )
    (property "MPN" "" (id 4) (at 58.42 244.475 0)
      (effects (font (size 1.27 1.27) (thickness 0.15)) (justify left bottom) hide)
    )
    (property "Manufacturer" "" (id 5) (at 58.42 241.935 0)
      (effects (font (size 1.27 1.27) (thickness 0.15)) (justify left bottom) hide)
    )
    (property "Author" "Antmicro" (id 6) (at 58.42 239.395 0)
      (effects (font (size 1.27 1.27) (thickness 0.15)) (justify left bottom) hide)
    )
    (property "License" "Apache-2.0" (id 7) (at 58.42 236.855 0)
      (effects (font (size 1.27 1.27) (thickness 0.15)) (justify left bottom) hide)
    )
    (pin "1")
  )

  (symbol (lib_id "sa800u-baseboard-hw:TP_0.75mm_SMD") (at 115.443 249.047 90) (unit 1)
    (in_bom yes) (on_board yes) (fields_autoplaced)
    (property "Reference" "TP105" (id 0) (at 116.84 245.8719 90)
      (effects (font (size 1.27 1.27)) (justify right))
    )
    (property "Value" "TP_0.75mm_SMD" (id 1) (at 117.983 249.047 0)
      (effects (font (size 1.27 1.27)) hide)
    )
    (property "Footprint" "sa800u-baseboard-hw-footprints:TP_SMD_0.75mm" (id 2) (at 110.363 243.967 0)
      (effects (font (size 1.524 1.524)) (justify left) hide)
    )
    (property "Datasheet" "" (id 3) (at 107.823 243.967 0)
      (effects (font (size 1.524 1.524)) (justify left) hide)
    )
    (property "MPN" "" (id 4) (at 130.683 231.267 0)
      (effects (font (size 1.27 1.27) (thickness 0.15)) (justify left bottom) hide)
    )
    (property "Manufacturer" "" (id 5) (at 133.223 231.267 0)
      (effects (font (size 1.27 1.27) (thickness 0.15)) (justify left bottom) hide)
    )
    (property "Author" "Antmicro" (id 6) (at 135.763 231.267 0)
      (effects (font (size 1.27 1.27) (thickness 0.15)) (justify left bottom) hide)
    )
    (property "License" "Apache-2.0" (id 7) (at 138.303 231.267 0)
      (effects (font (size 1.27 1.27) (thickness 0.15)) (justify left bottom) hide)
    )
    (pin "1")
  )

  (symbol (lib_id "sa800u-baseboard-hw:PWR_FLAG") (at 212.725 125.73 0) (mirror y) (unit 1)
    (in_bom yes) (on_board yes) (fields_autoplaced)
    (property "Reference" "#FLG011" (id 0) (at 212.725 123.825 0)
      (effects (font (size 1.27 1.27)) hide)
    )
    (property "Value" "PWR_FLAG" (id 1) (at 212.725 120.65 0))
    (property "Footprint" "" (id 2) (at 212.725 125.73 0)
      (effects (font (size 1.27 1.27)) hide)
    )
    (property "Datasheet" "" (id 3) (at 212.725 125.73 0)
      (effects (font (size 1.27 1.27)) hide)
    )
    (pin "1")
  )

  (symbol (lib_id "sa800u-baseboard-hw:PWR_FLAG") (at 283.21 125.73 0) (mirror y) (unit 1)
    (in_bom yes) (on_board yes) (fields_autoplaced)
    (property "Reference" "#FLG013" (id 0) (at 283.21 123.825 0)
      (effects (font (size 1.27 1.27)) hide)
    )
    (property "Value" "PWR_FLAG" (id 1) (at 283.21 120.65 0))
    (property "Footprint" "" (id 2) (at 283.21 125.73 0)
      (effects (font (size 1.27 1.27)) hide)
    )
    (property "Datasheet" "" (id 3) (at 283.21 125.73 0)
      (effects (font (size 1.27 1.27)) hide)
    )
    (pin "1")
  )

  (symbol (lib_id "sa800u-baseboard-hw:PWR_FLAG") (at 267.97 125.73 0) (mirror y) (unit 1)
    (in_bom yes) (on_board yes) (fields_autoplaced)
    (property "Reference" "#FLG012" (id 0) (at 267.97 123.825 0)
      (effects (font (size 1.27 1.27)) hide)
    )
    (property "Value" "PWR_FLAG" (id 1) (at 267.97 120.65 0))
    (property "Footprint" "" (id 2) (at 267.97 125.73 0)
      (effects (font (size 1.27 1.27)) hide)
    )
    (property "Datasheet" "" (id 3) (at 267.97 125.73 0)
      (effects (font (size 1.27 1.27)) hide)
    )
    (pin "1")
  )

  (symbol (lib_id "sa800u-baseboard-hw:TP_0.75mm_SMD") (at 115.57 254.127 90) (unit 1)
    (in_bom yes) (on_board yes) (fields_autoplaced)
    (property "Reference" "TP106" (id 0) (at 118.11 250.9519 90)
      (effects (font (size 1.27 1.27)) (justify right))
    )
    (property "Value" "TP_0.75mm_SMD" (id 1) (at 118.11 254.127 0)
      (effects (font (size 1.27 1.27)) hide)
    )
    (property "Footprint" "sa800u-baseboard-hw-footprints:TP_SMD_0.75mm" (id 2) (at 110.49 249.047 0)
      (effects (font (size 1.524 1.524)) (justify left) hide)
    )
    (property "Datasheet" "" (id 3) (at 107.95 249.047 0)
      (effects (font (size 1.524 1.524)) (justify left) hide)
    )
    (property "MPN" "" (id 4) (at 130.81 236.347 0)
      (effects (font (size 1.27 1.27) (thickness 0.15)) (justify left bottom) hide)
    )
    (property "Manufacturer" "" (id 5) (at 133.35 236.347 0)
      (effects (font (size 1.27 1.27) (thickness 0.15)) (justify left bottom) hide)
    )
    (property "Author" "Antmicro" (id 6) (at 135.89 236.347 0)
      (effects (font (size 1.27 1.27) (thickness 0.15)) (justify left bottom) hide)
    )
    (property "License" "Apache-2.0" (id 7) (at 138.43 236.347 0)
      (effects (font (size 1.27 1.27) (thickness 0.15)) (justify left bottom) hide)
    )
    (pin "1")
  )

  (symbol (lib_id "sa800u-baseboard-hw:TP_0.75mm_SMD") (at 115.697 259.08 90) (unit 1)
    (in_bom yes) (on_board yes) (fields_autoplaced)
    (property "Reference" "TP107" (id 0) (at 118.11 255.9049 90)
      (effects (font (size 1.27 1.27)) (justify right))
    )
    (property "Value" "TP_0.75mm_SMD" (id 1) (at 118.237 259.08 0)
      (effects (font (size 1.27 1.27)) hide)
    )
    (property "Footprint" "sa800u-baseboard-hw-footprints:TP_SMD_0.75mm" (id 2) (at 110.617 254 0)
      (effects (font (size 1.524 1.524)) (justify left) hide)
    )
    (property "Datasheet" "" (id 3) (at 108.077 254 0)
      (effects (font (size 1.524 1.524)) (justify left) hide)
    )
    (property "MPN" "" (id 4) (at 130.937 241.3 0)
      (effects (font (size 1.27 1.27) (thickness 0.15)) (justify left bottom) hide)
    )
    (property "Manufacturer" "" (id 5) (at 133.477 241.3 0)
      (effects (font (size 1.27 1.27) (thickness 0.15)) (justify left bottom) hide)
    )
    (property "Author" "Antmicro" (id 6) (at 136.017 241.3 0)
      (effects (font (size 1.27 1.27) (thickness 0.15)) (justify left bottom) hide)
    )
    (property "License" "Apache-2.0" (id 7) (at 138.557 241.3 0)
      (effects (font (size 1.27 1.27) (thickness 0.15)) (justify left bottom) hide)
    )
    (pin "1")
  )

  (symbol (lib_id "sa800u-baseboard-hw:C_47p_0402") (at 103.378 145.161 90) (mirror x) (unit 1)
    (in_bom yes) (on_board yes) (fields_autoplaced)
    (property "Reference" "C68" (id 0) (at 106.045 146.4373 90)
      (effects (font (size 1.524 1.524)) (justify right))
    )
    (property "Value" "C_47p_0402" (id 1) (at 107.188 145.161 0)
      (effects (font (size 1.524 1.524)) hide)
    )
    (property "Footprint" "sa800u-baseboard-hw-footprints:C_0402_1005Metric" (id 2) (at 98.298 150.241 0)
      (effects (font (size 1.524 1.524)) (justify left) hide)
    )
    (property "Datasheet" " " (id 3) (at 103.378 145.161 0)
      (effects (font (size 1.27 1.27)) hide)
    )
    (property "Manufacturer" "Murata" (id 4) (at 93.218 150.241 0)
      (effects (font (size 1.524 1.524)) (justify left) hide)
    )
    (property "MPN" "GRM1555C1E470JA01D" (id 5) (at 95.758 150.241 0)
      (effects (font (size 1.524 1.524)) (justify left) hide)
    )
    (property "Val" "47p" (id 6) (at 106.045 149.6122 90)
      (effects (font (size 1.27 1.27)) (justify right))
    )
    (property "License" "Apache-2.0" (id 7) (at 126.238 165.481 0)
      (effects (font (size 1.27 1.27) (thickness 0.15)) (justify left bottom) hide)
    )
    (property "Author" "Antmicro" (id 8) (at 128.778 165.481 0)
      (effects (font (size 1.27 1.27) (thickness 0.15)) (justify left bottom) hide)
    )
    (property "Voltage" "" (id 9) (at 131.318 165.481 0)
      (effects (font (size 1.27 1.27)) (justify left bottom) hide)
    )
    (property "Dielectric" "C0G" (id 10) (at 133.858 165.481 0)
      (effects (font (size 1.27 1.27)) (justify left bottom) hide)
    )
    (pin "1")
    (pin "2")
  )

  (symbol (lib_id "sa800u-baseboard-hw:C_47p_0402") (at 113.538 145.161 90) (mirror x) (unit 1)
    (in_bom yes) (on_board yes) (fields_autoplaced)
    (property "Reference" "C70" (id 0) (at 116.078 146.4373 90)
      (effects (font (size 1.524 1.524)) (justify right))
    )
    (property "Value" "C_47p_0402" (id 1) (at 117.348 145.161 0)
      (effects (font (size 1.524 1.524)) hide)
    )
    (property "Footprint" "sa800u-baseboard-hw-footprints:C_0402_1005Metric" (id 2) (at 108.458 150.241 0)
      (effects (font (size 1.524 1.524)) (justify left) hide)
    )
    (property "Datasheet" " " (id 3) (at 113.538 145.161 0)
      (effects (font (size 1.27 1.27)) hide)
    )
    (property "Manufacturer" "Murata" (id 4) (at 103.378 150.241 0)
      (effects (font (size 1.524 1.524)) (justify left) hide)
    )
    (property "MPN" "GRM1555C1E470JA01D" (id 5) (at 105.918 150.241 0)
      (effects (font (size 1.524 1.524)) (justify left) hide)
    )
    (property "Val" "47p" (id 6) (at 116.078 149.6122 90)
      (effects (font (size 1.27 1.27)) (justify right))
    )
    (property "License" "Apache-2.0" (id 7) (at 136.398 165.481 0)
      (effects (font (size 1.27 1.27) (thickness 0.15)) (justify left bottom) hide)
    )
    (property "Author" "Antmicro" (id 8) (at 138.938 165.481 0)
      (effects (font (size 1.27 1.27) (thickness 0.15)) (justify left bottom) hide)
    )
    (property "Voltage" "" (id 9) (at 141.478 165.481 0)
      (effects (font (size 1.27 1.27)) (justify left bottom) hide)
    )
    (property "Dielectric" "C0G" (id 10) (at 144.018 165.481 0)
      (effects (font (size 1.27 1.27)) (justify left bottom) hide)
    )
    (pin "1")
    (pin "2")
  )

  (symbol (lib_id "sa800u-baseboard-hw:GND") (at 103.378 150.241 0) (mirror y) (unit 1)
    (in_bom yes) (on_board yes) (fields_autoplaced)
    (property "Reference" "#PWR053" (id 0) (at 103.378 156.591 0)
      (effects (font (size 1.27 1.27)) hide)
    )
    (property "Value" "GND" (id 1) (at 103.378 155.321 0))
    (property "Footprint" "" (id 2) (at 103.378 150.241 0)
      (effects (font (size 1.27 1.27)) hide)
    )
    (property "Datasheet" "" (id 3) (at 103.378 150.241 0)
      (effects (font (size 1.27 1.27)) hide)
    )
    (property "Author" "Antmicro" (id 4) (at 94.488 157.861 0)
      (effects (font (size 1.27 1.27) (thickness 0.15)) (justify left bottom) hide)
    )
    (property "License" "Apache-2.0" (id 5) (at 94.488 160.401 0)
      (effects (font (size 1.27 1.27) (thickness 0.15)) (justify left bottom) hide)
    )
    (pin "1")
  )

  (symbol (lib_id "sa800u-baseboard-hw:GND") (at 113.538 150.241 0) (mirror y) (unit 1)
    (in_bom yes) (on_board yes) (fields_autoplaced)
    (property "Reference" "#PWR055" (id 0) (at 113.538 156.591 0)
      (effects (font (size 1.27 1.27)) hide)
    )
    (property "Value" "GND" (id 1) (at 113.538 155.321 0))
    (property "Footprint" "" (id 2) (at 113.538 150.241 0)
      (effects (font (size 1.27 1.27)) hide)
    )
    (property "Datasheet" "" (id 3) (at 113.538 150.241 0)
      (effects (font (size 1.27 1.27)) hide)
    )
    (property "Author" "Antmicro" (id 4) (at 104.648 157.861 0)
      (effects (font (size 1.27 1.27) (thickness 0.15)) (justify left bottom) hide)
    )
    (property "License" "Apache-2.0" (id 5) (at 104.648 160.401 0)
      (effects (font (size 1.27 1.27) (thickness 0.15)) (justify left bottom) hide)
    )
    (pin "1")
  )

  (symbol (lib_id "sa800u-baseboard-hw:GND") (at 316.865 243.205 0) (unit 1)
    (in_bom yes) (on_board yes) (fields_autoplaced)
    (property "Reference" "#PWR072" (id 0) (at 316.865 249.555 0)
      (effects (font (size 1.27 1.27)) hide)
    )
    (property "Value" "GND" (id 1) (at 316.865 247.65 0))
    (property "Footprint" "" (id 2) (at 316.865 243.205 0)
      (effects (font (size 1.27 1.27)) hide)
    )
    (property "Datasheet" "" (id 3) (at 316.865 243.205 0)
      (effects (font (size 1.27 1.27)) hide)
    )
    (property "Author" "Antmicro" (id 4) (at 325.755 250.825 0)
      (effects (font (size 1.27 1.27) (thickness 0.15)) (justify left bottom) hide)
    )
    (property "License" "Apache-2.0" (id 5) (at 325.755 253.365 0)
      (effects (font (size 1.27 1.27) (thickness 0.15)) (justify left bottom) hide)
    )
    (pin "1")
  )

  (symbol (lib_id "sa800u-baseboard-hw:GND") (at 347.345 243.205 0) (unit 1)
    (in_bom yes) (on_board yes) (fields_autoplaced)
    (property "Reference" "#PWR079" (id 0) (at 347.345 249.555 0)
      (effects (font (size 1.27 1.27)) hide)
    )
    (property "Value" "GND" (id 1) (at 347.345 247.65 0))
    (property "Footprint" "" (id 2) (at 347.345 243.205 0)
      (effects (font (size 1.27 1.27)) hide)
    )
    (property "Datasheet" "" (id 3) (at 347.345 243.205 0)
      (effects (font (size 1.27 1.27)) hide)
    )
    (property "Author" "Antmicro" (id 4) (at 356.235 250.825 0)
      (effects (font (size 1.27 1.27) (thickness 0.15)) (justify left bottom) hide)
    )
    (property "License" "Apache-2.0" (id 5) (at 356.235 253.365 0)
      (effects (font (size 1.27 1.27) (thickness 0.15)) (justify left bottom) hide)
    )
    (pin "1")
  )

  (symbol (lib_id "sa800u-baseboard-hw:C_100n_0402") (at 286.766 207.645 0) (unit 1)
    (in_bom yes) (on_board yes)
    (property "Reference" "C85" (id 0) (at 283.845 206.375 0)
      (effects (font (size 1.524 1.524)))
    )
    (property "Value" "C_100n_0402" (id 1) (at 286.766 211.455 0)
      (effects (font (size 1.524 1.524)) hide)
    )
    (property "Footprint" "sa800u-baseboard-hw-footprints:C_0402_1005Metric" (id 2) (at 291.846 202.565 0)
      (effects (font (size 1.524 1.524)) (justify left) hide)
    )
    (property "Datasheet" "https://search.murata.co.jp/Ceramy/image/img/A01X/G101/ENG/GRM155R61H104KE14-01.pdf" (id 3) (at 286.766 207.645 0)
      (effects (font (size 1.27 1.27)) hide)
    )
    (property "Manufacturer" "Murata" (id 4) (at 291.846 197.485 0)
      (effects (font (size 1.524 1.524)) (justify left) hide)
    )
    (property "MPN" "GRM155R61H104KE14D" (id 5) (at 291.846 200.025 0)
      (effects (font (size 1.524 1.524)) (justify left) hide)
    )
    (property "Val" "100n" (id 6) (at 292.735 206.629 0))
    (property "License" "Apache-2.0" (id 7) (at 307.086 230.505 0)
      (effects (font (size 1.27 1.27) (thickness 0.15)) (justify left bottom) hide)
    )
    (property "Author" "Antmicro" (id 8) (at 307.086 233.045 0)
      (effects (font (size 1.27 1.27) (thickness 0.15)) (justify left bottom) hide)
    )
    (property "Voltage" "50V" (id 9) (at 307.086 235.585 0)
      (effects (font (size 1.27 1.27)) (justify left bottom) hide)
    )
    (property "Dielectric" "X5R" (id 10) (at 307.086 238.125 0)
      (effects (font (size 1.27 1.27)) (justify left bottom) hide)
    )
    (pin "1")
    (pin "2")
  )

  (symbol (lib_id "sa800u-baseboard-hw:C_100n_0402") (at 284.226 210.185 0) (unit 1)
    (in_bom yes) (on_board yes)
    (property "Reference" "C81" (id 0) (at 283.845 209.042 0)
      (effects (font (size 1.524 1.524)))
    )
    (property "Value" "C_100n_0402" (id 1) (at 284.226 213.995 0)
      (effects (font (size 1.524 1.524)) hide)
    )
    (property "Footprint" "sa800u-baseboard-hw-footprints:C_0402_1005Metric" (id 2) (at 289.306 205.105 0)
      (effects (font (size 1.524 1.524)) (justify left) hide)
    )
    (property "Datasheet" "https://search.murata.co.jp/Ceramy/image/img/A01X/G101/ENG/GRM155R61H104KE14-01.pdf" (id 3) (at 284.226 210.185 0)
      (effects (font (size 1.27 1.27)) hide)
    )
    (property "Manufacturer" "Murata" (id 4) (at 289.306 200.025 0)
      (effects (font (size 1.524 1.524)) (justify left) hide)
    )
    (property "MPN" "GRM155R61H104KE14D" (id 5) (at 289.306 202.565 0)
      (effects (font (size 1.524 1.524)) (justify left) hide)
    )
    (property "Val" "100n" (id 6) (at 292.735 209.296 0))
    (property "License" "Apache-2.0" (id 7) (at 304.546 233.045 0)
      (effects (font (size 1.27 1.27) (thickness 0.15)) (justify left bottom) hide)
    )
    (property "Author" "Antmicro" (id 8) (at 304.546 235.585 0)
      (effects (font (size 1.27 1.27) (thickness 0.15)) (justify left bottom) hide)
    )
    (property "Voltage" "50V" (id 9) (at 304.546 238.125 0)
      (effects (font (size 1.27 1.27)) (justify left bottom) hide)
    )
    (property "Dielectric" "X5R" (id 10) (at 304.546 240.665 0)
      (effects (font (size 1.27 1.27)) (justify left bottom) hide)
    )
    (pin "1")
    (pin "2")
  )

  (symbol (lib_id "sa800u-baseboard-hw:C_100n_0402") (at 288.925 227.965 0) (unit 1)
    (in_bom yes) (on_board yes)
    (property "Reference" "C86" (id 0) (at 285.877 226.822 0)
      (effects (font (size 1.524 1.524)))
    )
    (property "Value" "C_100n_0402" (id 1) (at 288.925 231.775 0)
      (effects (font (size 1.524 1.524)) hide)
    )
    (property "Footprint" "sa800u-baseboard-hw-footprints:C_0402_1005Metric" (id 2) (at 294.005 222.885 0)
      (effects (font (size 1.524 1.524)) (justify left) hide)
    )
    (property "Datasheet" "https://search.murata.co.jp/Ceramy/image/img/A01X/G101/ENG/GRM155R61H104KE14-01.pdf" (id 3) (at 288.925 227.965 0)
      (effects (font (size 1.27 1.27)) hide)
    )
    (property "Manufacturer" "Murata" (id 4) (at 294.005 217.805 0)
      (effects (font (size 1.524 1.524)) (justify left) hide)
    )
    (property "MPN" "GRM155R61H104KE14D" (id 5) (at 294.005 220.345 0)
      (effects (font (size 1.524 1.524)) (justify left) hide)
    )
    (property "Val" "100n" (id 6) (at 294.64 226.822 0))
    (property "License" "Apache-2.0" (id 7) (at 309.245 250.825 0)
      (effects (font (size 1.27 1.27) (thickness 0.15)) (justify left bottom) hide)
    )
    (property "Author" "Antmicro" (id 8) (at 309.245 253.365 0)
      (effects (font (size 1.27 1.27) (thickness 0.15)) (justify left bottom) hide)
    )
    (property "Voltage" "50V" (id 9) (at 309.245 255.905 0)
      (effects (font (size 1.27 1.27)) (justify left bottom) hide)
    )
    (property "Dielectric" "X5R" (id 10) (at 309.245 258.445 0)
      (effects (font (size 1.27 1.27)) (justify left bottom) hide)
    )
    (pin "1")
    (pin "2")
  )

  (symbol (lib_id "sa800u-baseboard-hw:C_100n_0402") (at 286.385 230.505 0) (unit 1)
    (in_bom yes) (on_board yes)
    (property "Reference" "C82" (id 0) (at 285.877 229.362 0)
      (effects (font (size 1.524 1.524)))
    )
    (property "Value" "C_100n_0402" (id 1) (at 286.385 234.315 0)
      (effects (font (size 1.524 1.524)) hide)
    )
    (property "Footprint" "sa800u-baseboard-hw-footprints:C_0402_1005Metric" (id 2) (at 291.465 225.425 0)
      (effects (font (size 1.524 1.524)) (justify left) hide)
    )
    (property "Datasheet" "https://search.murata.co.jp/Ceramy/image/img/A01X/G101/ENG/GRM155R61H104KE14-01.pdf" (id 3) (at 286.385 230.505 0)
      (effects (font (size 1.27 1.27)) hide)
    )
    (property "Manufacturer" "Murata" (id 4) (at 291.465 220.345 0)
      (effects (font (size 1.524 1.524)) (justify left) hide)
    )
    (property "MPN" "GRM155R61H104KE14D" (id 5) (at 291.465 222.885 0)
      (effects (font (size 1.524 1.524)) (justify left) hide)
    )
    (property "Val" "100n" (id 6) (at 294.767 229.235 0))
    (property "License" "Apache-2.0" (id 7) (at 306.705 253.365 0)
      (effects (font (size 1.27 1.27) (thickness 0.15)) (justify left bottom) hide)
    )
    (property "Author" "Antmicro" (id 8) (at 306.705 255.905 0)
      (effects (font (size 1.27 1.27) (thickness 0.15)) (justify left bottom) hide)
    )
    (property "Voltage" "50V" (id 9) (at 306.705 258.445 0)
      (effects (font (size 1.27 1.27)) (justify left bottom) hide)
    )
    (property "Dielectric" "X5R" (id 10) (at 306.705 260.985 0)
      (effects (font (size 1.27 1.27)) (justify left bottom) hide)
    )
    (pin "1")
    (pin "2")
  )

  (symbol (lib_id "sa800u-baseboard-hw:C_100n_0402") (at 376.428 210.185 180) (unit 1)
    (in_bom yes) (on_board yes)
    (property "Reference" "C90" (id 0) (at 370.84 209.169 0)
      (effects (font (size 1.524 1.524)))
    )
    (property "Value" "C_100n_0402" (id 1) (at 376.428 206.375 0)
      (effects (font (size 1.524 1.524)) hide)
    )
    (property "Footprint" "sa800u-baseboard-hw-footprints:C_0402_1005Metric" (id 2) (at 371.348 215.265 0)
      (effects (font (size 1.524 1.524)) (justify left) hide)
    )
    (property "Datasheet" "https://search.murata.co.jp/Ceramy/image/img/A01X/G101/ENG/GRM155R61H104KE14-01.pdf" (id 3) (at 376.428 210.185 0)
      (effects (font (size 1.27 1.27)) hide)
    )
    (property "Manufacturer" "Murata" (id 4) (at 371.348 220.345 0)
      (effects (font (size 1.524 1.524)) (justify left) hide)
    )
    (property "MPN" "GRM155R61H104KE14D" (id 5) (at 371.348 217.805 0)
      (effects (font (size 1.524 1.524)) (justify left) hide)
    )
    (property "Val" "100n" (id 6) (at 379.603 209.169 0))
    (property "License" "Apache-2.0" (id 7) (at 356.108 187.325 0)
      (effects (font (size 1.27 1.27) (thickness 0.15)) (justify left bottom) hide)
    )
    (property "Author" "Antmicro" (id 8) (at 356.108 184.785 0)
      (effects (font (size 1.27 1.27) (thickness 0.15)) (justify left bottom) hide)
    )
    (property "Voltage" "50V" (id 9) (at 356.108 182.245 0)
      (effects (font (size 1.27 1.27)) (justify left bottom) hide)
    )
    (property "Dielectric" "X5R" (id 10) (at 356.108 179.705 0)
      (effects (font (size 1.27 1.27)) (justify left bottom) hide)
    )
    (pin "1")
    (pin "2")
  )

  (symbol (lib_id "sa800u-baseboard-hw:C_100n_0402") (at 378.968 207.645 180) (unit 1)
    (in_bom yes) (on_board yes)
    (property "Reference" "C94" (id 0) (at 370.84 206.502 0)
      (effects (font (size 1.524 1.524)))
    )
    (property "Value" "C_100n_0402" (id 1) (at 378.968 203.835 0)
      (effects (font (size 1.524 1.524)) hide)
    )
    (property "Footprint" "sa800u-baseboard-hw-footprints:C_0402_1005Metric" (id 2) (at 373.888 212.725 0)
      (effects (font (size 1.524 1.524)) (justify left) hide)
    )
    (property "Datasheet" "https://search.murata.co.jp/Ceramy/image/img/A01X/G101/ENG/GRM155R61H104KE14-01.pdf" (id 3) (at 378.968 207.645 0)
      (effects (font (size 1.27 1.27)) hide)
    )
    (property "Manufacturer" "Murata" (id 4) (at 373.888 217.805 0)
      (effects (font (size 1.524 1.524)) (justify left) hide)
    )
    (property "MPN" "GRM155R61H104KE14D" (id 5) (at 373.888 215.265 0)
      (effects (font (size 1.524 1.524)) (justify left) hide)
    )
    (property "Val" "100n" (id 6) (at 379.603 206.629 0))
    (property "License" "Apache-2.0" (id 7) (at 358.648 184.785 0)
      (effects (font (size 1.27 1.27) (thickness 0.15)) (justify left bottom) hide)
    )
    (property "Author" "Antmicro" (id 8) (at 358.648 182.245 0)
      (effects (font (size 1.27 1.27) (thickness 0.15)) (justify left bottom) hide)
    )
    (property "Voltage" "50V" (id 9) (at 358.648 179.705 0)
      (effects (font (size 1.27 1.27)) (justify left bottom) hide)
    )
    (property "Dielectric" "X5R" (id 10) (at 358.648 177.165 0)
      (effects (font (size 1.27 1.27)) (justify left bottom) hide)
    )
    (pin "1")
    (pin "2")
  )

  (symbol (lib_id "sa800u-baseboard-hw:C_100n_0402") (at 376.301 230.505 180) (unit 1)
    (in_bom yes) (on_board yes)
    (property "Reference" "C91" (id 0) (at 370.84 229.362 0)
      (effects (font (size 1.524 1.524)))
    )
    (property "Value" "C_100n_0402" (id 1) (at 376.301 226.695 0)
      (effects (font (size 1.524 1.524)) hide)
    )
    (property "Footprint" "sa800u-baseboard-hw-footprints:C_0402_1005Metric" (id 2) (at 371.221 235.585 0)
      (effects (font (size 1.524 1.524)) (justify left) hide)
    )
    (property "Datasheet" "https://search.murata.co.jp/Ceramy/image/img/A01X/G101/ENG/GRM155R61H104KE14-01.pdf" (id 3) (at 376.301 230.505 0)
      (effects (font (size 1.27 1.27)) hide)
    )
    (property "Manufacturer" "Murata" (id 4) (at 371.221 240.665 0)
      (effects (font (size 1.524 1.524)) (justify left) hide)
    )
    (property "MPN" "GRM155R61H104KE14D" (id 5) (at 371.221 238.125 0)
      (effects (font (size 1.524 1.524)) (justify left) hide)
    )
    (property "Val" "100n" (id 6) (at 379.476 229.489 0))
    (property "License" "Apache-2.0" (id 7) (at 355.981 207.645 0)
      (effects (font (size 1.27 1.27) (thickness 0.15)) (justify left bottom) hide)
    )
    (property "Author" "Antmicro" (id 8) (at 355.981 205.105 0)
      (effects (font (size 1.27 1.27) (thickness 0.15)) (justify left bottom) hide)
    )
    (property "Voltage" "50V" (id 9) (at 355.981 202.565 0)
      (effects (font (size 1.27 1.27)) (justify left bottom) hide)
    )
    (property "Dielectric" "X5R" (id 10) (at 355.981 200.025 0)
      (effects (font (size 1.27 1.27)) (justify left bottom) hide)
    )
    (pin "1")
    (pin "2")
  )

  (symbol (lib_id "sa800u-baseboard-hw:C_100n_0402") (at 378.841 227.965 180) (unit 1)
    (in_bom yes) (on_board yes)
    (property "Reference" "C95" (id 0) (at 370.84 226.822 0)
      (effects (font (size 1.524 1.524)))
    )
    (property "Value" "C_100n_0402" (id 1) (at 378.841 224.155 0)
      (effects (font (size 1.524 1.524)) hide)
    )
    (property "Footprint" "sa800u-baseboard-hw-footprints:C_0402_1005Metric" (id 2) (at 373.761 233.045 0)
      (effects (font (size 1.524 1.524)) (justify left) hide)
    )
    (property "Datasheet" "https://search.murata.co.jp/Ceramy/image/img/A01X/G101/ENG/GRM155R61H104KE14-01.pdf" (id 3) (at 378.841 227.965 0)
      (effects (font (size 1.27 1.27)) hide)
    )
    (property "Manufacturer" "Murata" (id 4) (at 373.761 238.125 0)
      (effects (font (size 1.524 1.524)) (justify left) hide)
    )
    (property "MPN" "GRM155R61H104KE14D" (id 5) (at 373.761 235.585 0)
      (effects (font (size 1.524 1.524)) (justify left) hide)
    )
    (property "Val" "100n" (id 6) (at 379.476 227.076 0))
    (property "License" "Apache-2.0" (id 7) (at 358.521 205.105 0)
      (effects (font (size 1.27 1.27) (thickness 0.15)) (justify left bottom) hide)
    )
    (property "Author" "Antmicro" (id 8) (at 358.521 202.565 0)
      (effects (font (size 1.27 1.27) (thickness 0.15)) (justify left bottom) hide)
    )
    (property "Voltage" "50V" (id 9) (at 358.521 200.025 0)
      (effects (font (size 1.27 1.27)) (justify left bottom) hide)
    )
    (property "Dielectric" "X5R" (id 10) (at 358.521 197.485 0)
      (effects (font (size 1.27 1.27)) (justify left bottom) hide)
    )
    (pin "1")
    (pin "2")
  )

  (symbol (lib_id "sa800u-baseboard-hw:TPS25820DSST") (at 73.66 190.5 0) (unit 1)
    (in_bom yes) (on_board yes) (fields_autoplaced)
    (property "Reference" "U6" (id 0) (at 83.82 182.88 0))
    (property "Value" "TPS25820DSST" (id 1) (at 83.82 185.42 0))
    (property "Footprint" "sa800u-baseboard-hw-footprints:WSON-12-1EP_2x3mm_P0.5mm" (id 2) (at 74.93 212.09 0)
      (effects (font (size 1.27 1.27)) hide)
    )
    (property "Datasheet" "https://www.ti.com/lit/ds/symlink/tps25820.pdf?ts=1624891405505&ref_url=https%253A%252F%252Fwww.ti.com%252Fproduct%252FTPS25820" (id 3) (at 73.66 190.5 0)
      (effects (font (size 1.27 1.27)) hide)
    )
    (property "Manufacturer" "Texas Instruments" (id 4) (at 73.66 207.01 0)
      (effects (font (size 1.27 1.27)) hide)
    )
    (property "MPN" "TPS25820DSST" (id 5) (at 73.66 209.55 0)
      (effects (font (size 1.27 1.27)) hide)
    )
    (property "Author" "Antmicro" (id 6) (at 109.22 210.82 0)
      (effects (font (size 1.27 1.27) (thickness 0.15)) (justify left bottom) hide)
    )
    (property "License" "Apache-2.0" (id 7) (at 109.22 213.36 0)
      (effects (font (size 1.27 1.27) (thickness 0.15)) (justify left bottom) hide)
    )
    (pin "1")
    (pin "10")
    (pin "11")
    (pin "12")
    (pin "13")
    (pin "2")
    (pin "3")
    (pin "4")
    (pin "5")
    (pin "6")
    (pin "7")
    (pin "8")
    (pin "9")
  )

  (symbol (lib_id "sa800u-baseboard-hw:CBTL02043ABQ,115") (at 207.01 237.49 0) (unit 1)
    (in_bom yes) (on_board yes) (fields_autoplaced)
    (property "Reference" "U9" (id 0) (at 219.71 229.87 0))
    (property "Value" "CBTL02043ABQ,115" (id 1) (at 219.71 232.41 0))
    (property "Footprint" "sa800u-baseboard-hw-footprints:DHVQFN-20-1EP_2.5x4.5_P0.5mm" (id 2) (at 191.77 265.43 0)
      (effects (font (size 1.27 1.27)) (justify left bottom) hide)
    )
    (property "Datasheet" "https://www.nxp.com/docs/en/data-sheet/CBTL02043A_CBTL02043B.pdf" (id 3) (at 207.01 237.49 0)
      (effects (font (size 1.27 1.27)) (justify left bottom) hide)
    )
    (property "MPN" "CBTL02043ABQ,115" (id 4) (at 207.01 262.89 0)
      (effects (font (size 1.27 1.27)) hide)
    )
    (property "Manufacturer" "Nexperia" (id 5) (at 205.74 260.35 0)
      (effects (font (size 1.27 1.27)) hide)
    )
    (property "Author" "Antmicro" (id 6) (at 245.11 256.54 0)
      (effects (font (size 1.27 1.27) (thickness 0.15)) (justify left bottom) hide)
    )
    (property "License" "Apache-2.0" (id 7) (at 245.11 259.08 0)
      (effects (font (size 1.27 1.27) (thickness 0.15)) (justify left bottom) hide)
    )
    (pin "1")
    (pin "10")
    (pin "11")
    (pin "12")
    (pin "13")
    (pin "14")
    (pin "15")
    (pin "16")
    (pin "17")
    (pin "18")
    (pin "19")
    (pin "2")
    (pin "20")
    (pin "21")
    (pin "3")
    (pin "4")
    (pin "5")
    (pin "6")
    (pin "7")
    (pin "8")
    (pin "9")
  )

  (symbol (lib_id "sa800u-baseboard-hw:GND") (at 205.74 271.78 0) (unit 1)
    (in_bom yes) (on_board yes) (fields_autoplaced)
    (property "Reference" "#PWR062" (id 0) (at 205.74 278.13 0)
      (effects (font (size 1.27 1.27)) hide)
    )
    (property "Value" "GND" (id 1) (at 205.74 276.86 0))
    (property "Footprint" "" (id 2) (at 205.74 271.78 0)
      (effects (font (size 1.27 1.27)) hide)
    )
    (property "Datasheet" "" (id 3) (at 205.74 271.78 0)
      (effects (font (size 1.27 1.27)) hide)
    )
    (property "Author" "Antmicro" (id 4) (at 214.63 279.4 0)
      (effects (font (size 1.27 1.27) (thickness 0.15)) (justify left bottom) hide)
    )
    (property "License" "Apache-2.0" (id 5) (at 214.63 281.94 0)
      (effects (font (size 1.27 1.27) (thickness 0.15)) (justify left bottom) hide)
    )
    (pin "1")
  )

  (symbol (lib_id "sa800u-baseboard-hw:C_47u_0603") (at 26.67 191.77 270) (unit 1)
    (in_bom yes) (on_board yes) (fields_autoplaced)
    (property "Reference" "C58" (id 0) (at 29.337 193.0463 90)
      (effects (font (size 1.524 1.524)) (justify left))
    )
    (property "Value" "C_47u_0603" (id 1) (at 22.86 191.77 0)
      (effects (font (size 1.524 1.524)) hide)
    )
    (property "Footprint" "sa800u-baseboard-hw-footprints:C_0603_1608Metric" (id 2) (at 31.75 196.85 0)
      (effects (font (size 1.524 1.524)) (justify left) hide)
    )
    (property "Datasheet" " " (id 3) (at 26.67 191.77 0)
      (effects (font (size 1.27 1.27)) hide)
    )
    (property "Manufacturer" "Murata" (id 4) (at 36.83 196.85 0)
      (effects (font (size 1.524 1.524)) (justify left) hide)
    )
    (property "MPN" "GRM188R60J476ME15D" (id 5) (at 34.29 196.85 0)
      (effects (font (size 1.524 1.524)) (justify left) hide)
    )
    (property "Val" "47u" (id 6) (at 29.337 196.2212 90)
      (effects (font (size 1.27 1.27)) (justify left))
    )
    (property "License" "Apache-2.0" (id 7) (at 3.81 212.09 0)
      (effects (font (size 1.27 1.27) (thickness 0.15)) (justify left bottom) hide)
    )
    (property "Author" "Antmicro" (id 8) (at 1.27 212.09 0)
      (effects (font (size 1.27 1.27) (thickness 0.15)) (justify left bottom) hide)
    )
    (property "Voltage" "" (id 9) (at -1.27 212.09 0)
      (effects (font (size 1.27 1.27)) (justify left bottom) hide)
    )
    (property "Dielectric" "" (id 10) (at -3.81 212.09 0)
      (effects (font (size 1.27 1.27)) (justify left bottom) hide)
    )
    (pin "1")
    (pin "2")
  )

  (symbol (lib_id "sa800u-baseboard-hw:C_47u_0603") (at 36.83 191.77 270) (unit 1)
    (in_bom yes) (on_board yes) (fields_autoplaced)
    (property "Reference" "C59" (id 0) (at 39.497 193.0463 90)
      (effects (font (size 1.524 1.524)) (justify left))
    )
    (property "Value" "C_47u_0603" (id 1) (at 33.02 191.77 0)
      (effects (font (size 1.524 1.524)) hide)
    )
    (property "Footprint" "sa800u-baseboard-hw-footprints:C_0603_1608Metric" (id 2) (at 41.91 196.85 0)
      (effects (font (size 1.524 1.524)) (justify left) hide)
    )
    (property "Datasheet" " " (id 3) (at 36.83 191.77 0)
      (effects (font (size 1.27 1.27)) hide)
    )
    (property "Manufacturer" "Murata" (id 4) (at 46.99 196.85 0)
      (effects (font (size 1.524 1.524)) (justify left) hide)
    )
    (property "MPN" "GRM188R60J476ME15D" (id 5) (at 44.45 196.85 0)
      (effects (font (size 1.524 1.524)) (justify left) hide)
    )
    (property "Val" "47u" (id 6) (at 39.497 196.2212 90)
      (effects (font (size 1.27 1.27)) (justify left))
    )
    (property "License" "Apache-2.0" (id 7) (at 13.97 212.09 0)
      (effects (font (size 1.27 1.27) (thickness 0.15)) (justify left bottom) hide)
    )
    (property "Author" "Antmicro" (id 8) (at 11.43 212.09 0)
      (effects (font (size 1.27 1.27) (thickness 0.15)) (justify left bottom) hide)
    )
    (property "Voltage" "" (id 9) (at 8.89 212.09 0)
      (effects (font (size 1.27 1.27)) (justify left bottom) hide)
    )
    (property "Dielectric" "" (id 10) (at 6.35 212.09 0)
      (effects (font (size 1.27 1.27)) (justify left bottom) hide)
    )
    (pin "1")
    (pin "2")
  )

  (symbol (lib_id "sa800u-baseboard-hw:C_47u_0603") (at 46.99 191.77 270) (unit 1)
    (in_bom yes) (on_board yes) (fields_autoplaced)
    (property "Reference" "C62" (id 0) (at 49.403 193.0463 90)
      (effects (font (size 1.524 1.524)) (justify left))
    )
    (property "Value" "C_47u_0603" (id 1) (at 43.18 191.77 0)
      (effects (font (size 1.524 1.524)) hide)
    )
    (property "Footprint" "sa800u-baseboard-hw-footprints:C_0603_1608Metric" (id 2) (at 52.07 196.85 0)
      (effects (font (size 1.524 1.524)) (justify left) hide)
    )
    (property "Datasheet" " " (id 3) (at 46.99 191.77 0)
      (effects (font (size 1.27 1.27)) hide)
    )
    (property "Manufacturer" "Murata" (id 4) (at 57.15 196.85 0)
      (effects (font (size 1.524 1.524)) (justify left) hide)
    )
    (property "MPN" "GRM188R60J476ME15D" (id 5) (at 54.61 196.85 0)
      (effects (font (size 1.524 1.524)) (justify left) hide)
    )
    (property "Val" "47u" (id 6) (at 49.403 196.2212 90)
      (effects (font (size 1.27 1.27)) (justify left))
    )
    (property "License" "Apache-2.0" (id 7) (at 24.13 212.09 0)
      (effects (font (size 1.27 1.27) (thickness 0.15)) (justify left bottom) hide)
    )
    (property "Author" "Antmicro" (id 8) (at 21.59 212.09 0)
      (effects (font (size 1.27 1.27) (thickness 0.15)) (justify left bottom) hide)
    )
    (property "Voltage" "" (id 9) (at 19.05 212.09 0)
      (effects (font (size 1.27 1.27)) (justify left bottom) hide)
    )
    (property "Dielectric" "" (id 10) (at 16.51 212.09 0)
      (effects (font (size 1.27 1.27)) (justify left bottom) hide)
    )
    (pin "1")
    (pin "2")
  )

  (symbol (lib_id "sa800u-baseboard-hw:GND") (at 26.67 200.66 0) (unit 1)
    (in_bom yes) (on_board yes) (fields_autoplaced)
    (property "Reference" "#PWR040" (id 0) (at 26.67 207.01 0)
      (effects (font (size 1.27 1.27)) hide)
    )
    (property "Value" "GND" (id 1) (at 26.67 205.74 0))
    (property "Footprint" "" (id 2) (at 26.67 200.66 0)
      (effects (font (size 1.27 1.27)) hide)
    )
    (property "Datasheet" "" (id 3) (at 26.67 200.66 0)
      (effects (font (size 1.27 1.27)) hide)
    )
    (property "Author" "Antmicro" (id 4) (at 35.56 208.28 0)
      (effects (font (size 1.27 1.27) (thickness 0.15)) (justify left bottom) hide)
    )
    (property "License" "Apache-2.0" (id 5) (at 35.56 210.82 0)
      (effects (font (size 1.27 1.27) (thickness 0.15)) (justify left bottom) hide)
    )
    (pin "1")
  )

  (symbol (lib_id "sa800u-baseboard-hw:GND") (at 57.15 201.93 0) (unit 1)
    (in_bom yes) (on_board yes) (fields_autoplaced)
    (property "Reference" "#PWR042" (id 0) (at 57.15 208.28 0)
      (effects (font (size 1.27 1.27)) hide)
    )
    (property "Value" "GND" (id 1) (at 57.15 207.01 0))
    (property "Footprint" "" (id 2) (at 57.15 201.93 0)
      (effects (font (size 1.27 1.27)) hide)
    )
    (property "Datasheet" "" (id 3) (at 57.15 201.93 0)
      (effects (font (size 1.27 1.27)) hide)
    )
    (property "Author" "Antmicro" (id 4) (at 66.04 209.55 0)
      (effects (font (size 1.27 1.27) (thickness 0.15)) (justify left bottom) hide)
    )
    (property "License" "Apache-2.0" (id 5) (at 66.04 212.09 0)
      (effects (font (size 1.27 1.27) (thickness 0.15)) (justify left bottom) hide)
    )
    (pin "1")
  )

  (symbol (lib_id "sa800u-baseboard-hw:R_100k_0.5%_0402") (at 64.77 209.169 270) (unit 1)
    (in_bom yes) (on_board yes) (fields_autoplaced)
    (property "Reference" "R59" (id 0) (at 62.23 210.439 90)
      (effects (font (size 1.524 1.524)) (justify right))
    )
    (property "Value" "R_100k_0.5%_0402" (id 1) (at 60.96 209.169 0)
      (effects (font (size 1.524 1.524)) hide)
    )
    (property "Footprint" "sa800u-baseboard-hw-footprints:R_0402_1005Metric" (id 2) (at 69.85 214.249 0)
      (effects (font (size 1.524 1.524)) (justify left) hide)
    )
    (property "Datasheet" "" (id 3) (at 64.77 209.169 0)
      (effects (font (size 1.27 1.27)) hide)
    )
    (property "Manufacturer" "Panasonic" (id 4) (at 74.93 214.249 0)
      (effects (font (size 1.524 1.524)) (justify left) hide)
    )
    (property "MPN" "ERA2AED104X" (id 5) (at 72.39 214.249 0)
      (effects (font (size 1.524 1.524)) (justify left) hide)
    )
    (property "Val" "100k_0.5%" (id 6) (at 62.23 213.6139 90)
      (effects (font (size 1.27 1.27)) (justify right))
    )
    (property "Author" "Antmicro" (id 7) (at 41.91 224.409 0)
      (effects (font (size 1.27 1.27) (thickness 0.15)) (justify left bottom) hide)
    )
    (property "License" "Apache-2.0" (id 8) (at 39.37 224.409 0)
      (effects (font (size 1.27 1.27) (thickness 0.15)) (justify left bottom) hide)
    )
    (pin "1")
    (pin "2")
  )

  (symbol (lib_id "sa800u-baseboard-hw:GND") (at 64.77 217.17 0) (unit 1)
    (in_bom yes) (on_board yes) (fields_autoplaced)
    (property "Reference" "#PWR045" (id 0) (at 64.77 223.52 0)
      (effects (font (size 1.27 1.27)) hide)
    )
    (property "Value" "GND" (id 1) (at 64.77 222.25 0))
    (property "Footprint" "" (id 2) (at 64.77 217.17 0)
      (effects (font (size 1.27 1.27)) hide)
    )
    (property "Datasheet" "" (id 3) (at 64.77 217.17 0)
      (effects (font (size 1.27 1.27)) hide)
    )
    (property "Author" "Antmicro" (id 4) (at 73.66 224.79 0)
      (effects (font (size 1.27 1.27) (thickness 0.15)) (justify left bottom) hide)
    )
    (property "License" "Apache-2.0" (id 5) (at 73.66 227.33 0)
      (effects (font (size 1.27 1.27) (thickness 0.15)) (justify left bottom) hide)
    )
    (pin "1")
  )

  (symbol (lib_id "sa800u-baseboard-hw:R_100k_0402") (at 96.52 215.138 270) (unit 1)
    (in_bom yes) (on_board yes)
    (property "Reference" "R60" (id 0) (at 97.028 214.63 90)
      (effects (font (size 1.524 1.524)) (justify left))
    )
    (property "Value" "R_100k_0402" (id 1) (at 92.71 215.138 0)
      (effects (font (size 1.524 1.524)) hide)
    )
    (property "Footprint" "sa800u-baseboard-hw-footprints:R_0402_1005Metric" (id 2) (at 101.6 220.218 0)
      (effects (font (size 1.524 1.524)) (justify left) hide)
    )
    (property "Datasheet" "https://www.bourns.com/docs/product-datasheets/cr.pdf" (id 3) (at 96.52 215.138 0)
      (effects (font (size 1.27 1.27)) hide)
    )
    (property "Manufacturer" "Bourns" (id 4) (at 106.68 220.218 0)
      (effects (font (size 1.524 1.524)) (justify left) hide)
    )
    (property "MPN" "CR0402-FX-1003GLF" (id 5) (at 104.14 220.218 0)
      (effects (font (size 1.524 1.524)) (justify left) hide)
    )
    (property "Val" "100k" (id 6) (at 97.028 220.726 90)
      (effects (font (size 1.27 1.27)) (justify left))
    )
    (property "License" "Apache-2.0" (id 7) (at 71.12 235.458 0)
      (effects (font (size 1.27 1.27) (thickness 0.15)) (justify left bottom) hide)
    )
    (property "Author" "Antmicro" (id 8) (at 68.58 235.458 0)
      (effects (font (size 1.27 1.27) (thickness 0.15)) (justify left bottom) hide)
    )
    (property "Tolerance" "1%" (id 9) (at 86.36 235.458 0)
      (effects (font (size 1.27 1.27)) (justify left bottom) hide)
    )
    (pin "1")
    (pin "2")
  )

  (symbol (lib_id "sa800u-baseboard-hw:R_100k_0402") (at 104.14 215.138 270) (unit 1)
    (in_bom yes) (on_board yes)
    (property "Reference" "R61" (id 0) (at 104.648 214.63 90)
      (effects (font (size 1.524 1.524)) (justify left))
    )
    (property "Value" "R_100k_0402" (id 1) (at 100.33 215.138 0)
      (effects (font (size 1.524 1.524)) hide)
    )
    (property "Footprint" "sa800u-baseboard-hw-footprints:R_0402_1005Metric" (id 2) (at 109.22 220.218 0)
      (effects (font (size 1.524 1.524)) (justify left) hide)
    )
    (property "Datasheet" "https://www.bourns.com/docs/product-datasheets/cr.pdf" (id 3) (at 104.14 215.138 0)
      (effects (font (size 1.27 1.27)) hide)
    )
    (property "Manufacturer" "Bourns" (id 4) (at 114.3 220.218 0)
      (effects (font (size 1.524 1.524)) (justify left) hide)
    )
    (property "MPN" "CR0402-FX-1003GLF" (id 5) (at 111.76 220.218 0)
      (effects (font (size 1.524 1.524)) (justify left) hide)
    )
    (property "Val" "100k" (id 6) (at 104.648 220.726 90)
      (effects (font (size 1.27 1.27)) (justify left))
    )
    (property "License" "Apache-2.0" (id 7) (at 78.74 235.458 0)
      (effects (font (size 1.27 1.27) (thickness 0.15)) (justify left bottom) hide)
    )
    (property "Author" "Antmicro" (id 8) (at 76.2 235.458 0)
      (effects (font (size 1.27 1.27) (thickness 0.15)) (justify left bottom) hide)
    )
    (property "Tolerance" "1%" (id 9) (at 93.98 235.458 0)
      (effects (font (size 1.27 1.27)) (justify left bottom) hide)
    )
    (pin "1")
    (pin "2")
  )

  (symbol (lib_id "sa800u-baseboard-hw:R_100k_0402") (at 111.76 215.138 270) (unit 1)
    (in_bom yes) (on_board yes)
    (property "Reference" "R63" (id 0) (at 112.268 214.63 90)
      (effects (font (size 1.524 1.524)) (justify left))
    )
    (property "Value" "R_100k_0402" (id 1) (at 107.95 215.138 0)
      (effects (font (size 1.524 1.524)) hide)
    )
    (property "Footprint" "sa800u-baseboard-hw-footprints:R_0402_1005Metric" (id 2) (at 116.84 220.218 0)
      (effects (font (size 1.524 1.524)) (justify left) hide)
    )
    (property "Datasheet" "https://www.bourns.com/docs/product-datasheets/cr.pdf" (id 3) (at 111.76 215.138 0)
      (effects (font (size 1.27 1.27)) hide)
    )
    (property "Manufacturer" "Bourns" (id 4) (at 121.92 220.218 0)
      (effects (font (size 1.524 1.524)) (justify left) hide)
    )
    (property "MPN" "CR0402-FX-1003GLF" (id 5) (at 119.38 220.218 0)
      (effects (font (size 1.524 1.524)) (justify left) hide)
    )
    (property "Val" "100k" (id 6) (at 112.268 220.726 90)
      (effects (font (size 1.27 1.27)) (justify left))
    )
    (property "License" "Apache-2.0" (id 7) (at 86.36 235.458 0)
      (effects (font (size 1.27 1.27) (thickness 0.15)) (justify left bottom) hide)
    )
    (property "Author" "Antmicro" (id 8) (at 83.82 235.458 0)
      (effects (font (size 1.27 1.27) (thickness 0.15)) (justify left bottom) hide)
    )
    (property "Tolerance" "1%" (id 9) (at 101.6 235.458 0)
      (effects (font (size 1.27 1.27)) (justify left bottom) hide)
    )
    (pin "1")
    (pin "2")
  )

  (symbol (lib_id "sa800u-baseboard-hw:C_10u_0402") (at 118.11 191.516 270) (unit 1)
    (in_bom yes) (on_board yes) (fields_autoplaced)
    (property "Reference" "C71" (id 0) (at 120.777 192.7923 90)
      (effects (font (size 1.524 1.524)) (justify left))
    )
    (property "Value" "C_10u_0402" (id 1) (at 114.3 191.516 0)
      (effects (font (size 1.524 1.524)) hide)
    )
    (property "Footprint" "sa800u-baseboard-hw-footprints:C_0402_1005Metric" (id 2) (at 123.19 196.596 0)
      (effects (font (size 1.524 1.524)) (justify left) hide)
    )
    (property "Datasheet" " " (id 3) (at 118.11 191.516 0)
      (effects (font (size 1.27 1.27)) hide)
    )
    (property "Manufacturer" "Yaego" (id 4) (at 128.27 196.596 0)
      (effects (font (size 1.524 1.524)) (justify left) hide)
    )
    (property "MPN" "CC0402MRX5R5BB106" (id 5) (at 125.73 196.596 0)
      (effects (font (size 1.524 1.524)) (justify left) hide)
    )
    (property "Val" "10u" (id 6) (at 120.777 195.9672 90)
      (effects (font (size 1.27 1.27)) (justify left))
    )
    (property "License" "Apache-2.0" (id 7) (at 95.25 211.836 0)
      (effects (font (size 1.27 1.27) (thickness 0.15)) (justify left bottom) hide)
    )
    (property "Author" "Antmicro" (id 8) (at 92.71 211.836 0)
      (effects (font (size 1.27 1.27) (thickness 0.15)) (justify left bottom) hide)
    )
    (property "Voltage" "" (id 9) (at 90.17 211.836 0)
      (effects (font (size 1.27 1.27)) (justify left bottom) hide)
    )
    (property "Dielectric" "" (id 10) (at 87.63 211.836 0)
      (effects (font (size 1.27 1.27)) (justify left bottom) hide)
    )
    (pin "1")
    (pin "2")
  )

  (symbol (lib_id "sa800u-baseboard-hw:GND") (at 118.11 196.596 0) (unit 1)
    (in_bom yes) (on_board yes) (fields_autoplaced)
    (property "Reference" "#PWR056" (id 0) (at 118.11 202.946 0)
      (effects (font (size 1.27 1.27)) hide)
    )
    (property "Value" "GND" (id 1) (at 115.57 197.8659 0)
      (effects (font (size 1.27 1.27)) (justify right))
    )
    (property "Footprint" "" (id 2) (at 118.11 196.596 0)
      (effects (font (size 1.27 1.27)) hide)
    )
    (property "Datasheet" "" (id 3) (at 118.11 196.596 0)
      (effects (font (size 1.27 1.27)) hide)
    )
    (property "Author" "Antmicro" (id 4) (at 127 204.216 0)
      (effects (font (size 1.27 1.27) (thickness 0.15)) (justify left bottom) hide)
    )
    (property "License" "Apache-2.0" (id 5) (at 127 206.756 0)
      (effects (font (size 1.27 1.27) (thickness 0.15)) (justify left bottom) hide)
    )
    (pin "1")
  )

  (symbol (lib_id "sa800u-baseboard-hw:GND") (at 201.295 271.78 0) (unit 1)
    (in_bom yes) (on_board yes) (fields_autoplaced)
    (property "Reference" "#PWR060" (id 0) (at 201.295 278.13 0)
      (effects (font (size 1.27 1.27)) hide)
    )
    (property "Value" "GND" (id 1) (at 201.295 276.86 0))
    (property "Footprint" "" (id 2) (at 201.295 271.78 0)
      (effects (font (size 1.27 1.27)) hide)
    )
    (property "Datasheet" "" (id 3) (at 201.295 271.78 0)
      (effects (font (size 1.27 1.27)) hide)
    )
    (property "Author" "Antmicro" (id 4) (at 210.185 279.4 0)
      (effects (font (size 1.27 1.27) (thickness 0.15)) (justify left bottom) hide)
    )
    (property "License" "Apache-2.0" (id 5) (at 210.185 281.94 0)
      (effects (font (size 1.27 1.27) (thickness 0.15)) (justify left bottom) hide)
    )
    (pin "1")
  )

  (symbol (lib_id "sa800u-baseboard-hw:R_200k_0402") (at 201.295 266.7 270) (unit 1)
    (in_bom yes) (on_board yes) (fields_autoplaced)
    (property "Reference" "R64" (id 0) (at 199.39 267.97 90)
      (effects (font (size 1.524 1.524)) (justify right))
    )
    (property "Value" "R_200k_0402" (id 1) (at 197.485 266.7 0)
      (effects (font (size 1.524 1.524)) hide)
    )
    (property "Footprint" "sa800u-baseboard-hw-footprints:R_0402_1005Metric" (id 2) (at 206.375 271.78 0)
      (effects (font (size 1.524 1.524)) (justify left) hide)
    )
    (property "Datasheet" "https://www.bourns.com/docs/product-datasheets/cr.pdf" (id 3) (at 201.295 266.7 0)
      (effects (font (size 1.27 1.27)) hide)
    )
    (property "Manufacturer" "Bourns" (id 4) (at 211.455 271.78 0)
      (effects (font (size 1.524 1.524)) (justify left) hide)
    )
    (property "MPN" "CR0402-FX-2003GLF" (id 5) (at 208.915 271.78 0)
      (effects (font (size 1.524 1.524)) (justify left) hide)
    )
    (property "Val" "200k" (id 6) (at 199.39 271.1449 90)
      (effects (font (size 1.27 1.27)) (justify right))
    )
    (property "License" "Apache-2.0" (id 7) (at 175.895 287.02 0)
      (effects (font (size 1.27 1.27) (thickness 0.15)) (justify left bottom) hide)
    )
    (property "Author" "Antmicro" (id 8) (at 173.355 287.02 0)
      (effects (font (size 1.27 1.27) (thickness 0.15)) (justify left bottom) hide)
    )
    (property "Tolerance" "1%" (id 9) (at 191.135 287.02 0)
      (effects (font (size 1.27 1.27)) (justify left bottom) hide)
    )
    (pin "1")
    (pin "2")
  )

  (symbol (lib_id "sa800u-baseboard-hw:C_100n_0402") (at 169.418 238.252 270) (unit 1)
    (in_bom yes) (on_board yes) (fields_autoplaced)
    (property "Reference" "C74" (id 0) (at 172.466 239.5283 90)
      (effects (font (size 1.524 1.524)) (justify left))
    )
    (property "Value" "C_100n_0402" (id 1) (at 165.608 238.252 0)
      (effects (font (size 1.524 1.524)) hide)
    )
    (property "Footprint" "sa800u-baseboard-hw-footprints:C_0402_1005Metric" (id 2) (at 174.498 243.332 0)
      (effects (font (size 1.524 1.524)) (justify left) hide)
    )
    (property "Datasheet" "https://search.murata.co.jp/Ceramy/image/img/A01X/G101/ENG/GRM155R61H104KE14-01.pdf" (id 3) (at 169.418 238.252 0)
      (effects (font (size 1.27 1.27)) hide)
    )
    (property "Manufacturer" "Murata" (id 4) (at 179.578 243.332 0)
      (effects (font (size 1.524 1.524)) (justify left) hide)
    )
    (property "MPN" "GRM155R61H104KE14D" (id 5) (at 177.038 243.332 0)
      (effects (font (size 1.524 1.524)) (justify left) hide)
    )
    (property "Val" "100n" (id 6) (at 172.466 242.7032 90)
      (effects (font (size 1.27 1.27)) (justify left))
    )
    (property "License" "Apache-2.0" (id 7) (at 146.558 258.572 0)
      (effects (font (size 1.27 1.27) (thickness 0.15)) (justify left bottom) hide)
    )
    (property "Author" "Antmicro" (id 8) (at 144.018 258.572 0)
      (effects (font (size 1.27 1.27) (thickness 0.15)) (justify left bottom) hide)
    )
    (property "Voltage" "50V" (id 9) (at 141.478 258.572 0)
      (effects (font (size 1.27 1.27)) (justify left bottom) hide)
    )
    (property "Dielectric" "X5R" (id 10) (at 138.938 258.572 0)
      (effects (font (size 1.27 1.27)) (justify left bottom) hide)
    )
    (pin "1")
    (pin "2")
  )

  (symbol (lib_id "sa800u-baseboard-hw:C_100n_0402") (at 159.893 238.252 270) (unit 1)
    (in_bom yes) (on_board yes)
    (property "Reference" "C73" (id 0) (at 163.068 239.5283 90)
      (effects (font (size 1.524 1.524)) (justify left))
    )
    (property "Value" "C_100n_0402" (id 1) (at 156.083 238.252 0)
      (effects (font (size 1.524 1.524)) hide)
    )
    (property "Footprint" "sa800u-baseboard-hw-footprints:C_0402_1005Metric" (id 2) (at 164.973 243.332 0)
      (effects (font (size 1.524 1.524)) (justify left) hide)
    )
    (property "Datasheet" "https://search.murata.co.jp/Ceramy/image/img/A01X/G101/ENG/GRM155R61H104KE14-01.pdf" (id 3) (at 159.893 238.252 0)
      (effects (font (size 1.27 1.27)) hide)
    )
    (property "Manufacturer" "Murata" (id 4) (at 170.053 243.332 0)
      (effects (font (size 1.524 1.524)) (justify left) hide)
    )
    (property "MPN" "GRM155R61H104KE14D" (id 5) (at 167.513 243.332 0)
      (effects (font (size 1.524 1.524)) (justify left) hide)
    )
    (property "Val" "100n" (id 6) (at 163.068 242.7032 90)
      (effects (font (size 1.27 1.27)) (justify left))
    )
    (property "License" "Apache-2.0" (id 7) (at 137.033 258.572 0)
      (effects (font (size 1.27 1.27) (thickness 0.15)) (justify left bottom) hide)
    )
    (property "Author" "Antmicro" (id 8) (at 134.493 258.572 0)
      (effects (font (size 1.27 1.27) (thickness 0.15)) (justify left bottom) hide)
    )
    (property "Voltage" "50V" (id 9) (at 131.953 258.572 0)
      (effects (font (size 1.27 1.27)) (justify left bottom) hide)
    )
    (property "Dielectric" "X5R" (id 10) (at 129.413 258.572 0)
      (effects (font (size 1.27 1.27)) (justify left bottom) hide)
    )
    (pin "1")
    (pin "2")
  )

  (symbol (lib_id "sa800u-baseboard-hw:C_100n_0402") (at 151.765 238.252 270) (unit 1)
    (in_bom yes) (on_board yes)
    (property "Reference" "C72" (id 0) (at 157.226 238.887 90)
      (effects (font (size 1.524 1.524)) (justify right))
    )
    (property "Value" "C_100n_0402" (id 1) (at 147.955 238.252 0)
      (effects (font (size 1.524 1.524)) hide)
    )
    (property "Footprint" "sa800u-baseboard-hw-footprints:C_0402_1005Metric" (id 2) (at 156.845 243.332 0)
      (effects (font (size 1.524 1.524)) (justify left) hide)
    )
    (property "Datasheet" "https://search.murata.co.jp/Ceramy/image/img/A01X/G101/ENG/GRM155R61H104KE14-01.pdf" (id 3) (at 151.765 238.252 0)
      (effects (font (size 1.27 1.27)) hide)
    )
    (property "Manufacturer" "Murata" (id 4) (at 161.925 243.332 0)
      (effects (font (size 1.524 1.524)) (justify left) hide)
    )
    (property "MPN" "GRM155R61H104KE14D" (id 5) (at 159.385 243.332 0)
      (effects (font (size 1.524 1.524)) (justify left) hide)
    )
    (property "Val" "100n" (id 6) (at 157.48 242.697 90)
      (effects (font (size 1.27 1.27)) (justify right))
    )
    (property "License" "Apache-2.0" (id 7) (at 128.905 258.572 0)
      (effects (font (size 1.27 1.27) (thickness 0.15)) (justify left bottom) hide)
    )
    (property "Author" "Antmicro" (id 8) (at 126.365 258.572 0)
      (effects (font (size 1.27 1.27) (thickness 0.15)) (justify left bottom) hide)
    )
    (property "Voltage" "50V" (id 9) (at 123.825 258.572 0)
      (effects (font (size 1.27 1.27)) (justify left bottom) hide)
    )
    (property "Dielectric" "X5R" (id 10) (at 121.285 258.572 0)
      (effects (font (size 1.27 1.27)) (justify left bottom) hide)
    )
    (pin "1")
    (pin "2")
  )

  (symbol (lib_id "sa800u-baseboard-hw:C_47u_0603") (at 244.475 197.485 270) (unit 1)
    (in_bom yes) (on_board yes) (fields_autoplaced)
    (property "Reference" "C76" (id 0) (at 247.65 198.7613 90)
      (effects (font (size 1.524 1.524)) (justify left))
    )
    (property "Value" "C_47u_0603" (id 1) (at 240.665 197.485 0)
      (effects (font (size 1.524 1.524)) hide)
    )
    (property "Footprint" "sa800u-baseboard-hw-footprints:C_0603_1608Metric" (id 2) (at 249.555 202.565 0)
      (effects (font (size 1.524 1.524)) (justify left) hide)
    )
    (property "Datasheet" " " (id 3) (at 244.475 197.485 0)
      (effects (font (size 1.27 1.27)) hide)
    )
    (property "Manufacturer" "Murata" (id 4) (at 254.635 202.565 0)
      (effects (font (size 1.524 1.524)) (justify left) hide)
    )
    (property "MPN" "GRM188R60J476ME15D" (id 5) (at 252.095 202.565 0)
      (effects (font (size 1.524 1.524)) (justify left) hide)
    )
    (property "Val" "47u" (id 6) (at 247.65 201.9362 90)
      (effects (font (size 1.27 1.27)) (justify left))
    )
    (property "License" "Apache-2.0" (id 7) (at 221.615 217.805 0)
      (effects (font (size 1.27 1.27) (thickness 0.15)) (justify left bottom) hide)
    )
    (property "Author" "Antmicro" (id 8) (at 219.075 217.805 0)
      (effects (font (size 1.27 1.27) (thickness 0.15)) (justify left bottom) hide)
    )
    (property "Voltage" "" (id 9) (at 216.535 217.805 0)
      (effects (font (size 1.27 1.27)) (justify left bottom) hide)
    )
    (property "Dielectric" "" (id 10) (at 213.995 217.805 0)
      (effects (font (size 1.27 1.27)) (justify left bottom) hide)
    )
    (pin "1")
    (pin "2")
  )

  (symbol (lib_id "sa800u-baseboard-hw:C_47u_0603") (at 254.635 197.485 270) (unit 1)
    (in_bom yes) (on_board yes) (fields_autoplaced)
    (property "Reference" "C78" (id 0) (at 257.683 198.7613 90)
      (effects (font (size 1.524 1.524)) (justify left))
    )
    (property "Value" "C_47u_0603" (id 1) (at 250.825 197.485 0)
      (effects (font (size 1.524 1.524)) hide)
    )
    (property "Footprint" "sa800u-baseboard-hw-footprints:C_0603_1608Metric" (id 2) (at 259.715 202.565 0)
      (effects (font (size 1.524 1.524)) (justify left) hide)
    )
    (property "Datasheet" " " (id 3) (at 254.635 197.485 0)
      (effects (font (size 1.27 1.27)) hide)
    )
    (property "Manufacturer" "Murata" (id 4) (at 264.795 202.565 0)
      (effects (font (size 1.524 1.524)) (justify left) hide)
    )
    (property "MPN" "GRM188R60J476ME15D" (id 5) (at 262.255 202.565 0)
      (effects (font (size 1.524 1.524)) (justify left) hide)
    )
    (property "Val" "47u" (id 6) (at 257.683 201.9362 90)
      (effects (font (size 1.27 1.27)) (justify left))
    )
    (property "License" "Apache-2.0" (id 7) (at 231.775 217.805 0)
      (effects (font (size 1.27 1.27) (thickness 0.15)) (justify left bottom) hide)
    )
    (property "Author" "Antmicro" (id 8) (at 229.235 217.805 0)
      (effects (font (size 1.27 1.27) (thickness 0.15)) (justify left bottom) hide)
    )
    (property "Voltage" "" (id 9) (at 226.695 217.805 0)
      (effects (font (size 1.27 1.27)) (justify left bottom) hide)
    )
    (property "Dielectric" "" (id 10) (at 224.155 217.805 0)
      (effects (font (size 1.27 1.27)) (justify left bottom) hide)
    )
    (pin "1")
    (pin "2")
  )

  (symbol (lib_id "sa800u-baseboard-hw:GND") (at 254.635 203.835 0) (unit 1)
    (in_bom yes) (on_board yes) (fields_autoplaced)
    (property "Reference" "#PWR067" (id 0) (at 254.635 210.185 0)
      (effects (font (size 1.27 1.27)) hide)
    )
    (property "Value" "GND" (id 1) (at 254.635 208.28 0))
    (property "Footprint" "" (id 2) (at 254.635 203.835 0)
      (effects (font (size 1.27 1.27)) hide)
    )
    (property "Datasheet" "" (id 3) (at 254.635 203.835 0)
      (effects (font (size 1.27 1.27)) hide)
    )
    (property "Author" "Antmicro" (id 4) (at 263.525 211.455 0)
      (effects (font (size 1.27 1.27) (thickness 0.15)) (justify left bottom) hide)
    )
    (property "License" "Apache-2.0" (id 5) (at 263.525 213.995 0)
      (effects (font (size 1.27 1.27) (thickness 0.15)) (justify left bottom) hide)
    )
    (pin "1")
  )

  (symbol (lib_id "sa800u-baseboard-hw:GND") (at 151.765 245.745 0) (unit 1)
    (in_bom yes) (on_board yes) (fields_autoplaced)
    (property "Reference" "#PWR058" (id 0) (at 151.765 252.095 0)
      (effects (font (size 1.27 1.27)) hide)
    )
    (property "Value" "GND" (id 1) (at 151.765 250.19 0))
    (property "Footprint" "" (id 2) (at 151.765 245.745 0)
      (effects (font (size 1.27 1.27)) hide)
    )
    (property "Datasheet" "" (id 3) (at 151.765 245.745 0)
      (effects (font (size 1.27 1.27)) hide)
    )
    (property "Author" "Antmicro" (id 4) (at 160.655 253.365 0)
      (effects (font (size 1.27 1.27) (thickness 0.15)) (justify left bottom) hide)
    )
    (property "License" "Apache-2.0" (id 5) (at 160.655 255.905 0)
      (effects (font (size 1.27 1.27) (thickness 0.15)) (justify left bottom) hide)
    )
    (pin "1")
  )

  (symbol (lib_id "sa800u-baseboard-hw:C_100n_0402") (at 125.984 127.381 90) (mirror x) (unit 1)
    (in_bom yes) (on_board yes) (fields_autoplaced)
    (property "Reference" "C64" (id 0) (at 123.571 128.6573 90)
      (effects (font (size 1.524 1.524)) (justify left))
    )
    (property "Value" "C_100n_0402" (id 1) (at 129.794 127.381 0)
      (effects (font (size 1.524 1.524)) hide)
    )
    (property "Footprint" "sa800u-baseboard-hw-footprints:C_0402_1005Metric" (id 2) (at 120.904 132.461 0)
      (effects (font (size 1.524 1.524)) (justify left) hide)
    )
    (property "Datasheet" "https://search.murata.co.jp/Ceramy/image/img/A01X/G101/ENG/GRM155R61H104KE14-01.pdf" (id 3) (at 125.984 127.381 0)
      (effects (font (size 1.27 1.27)) hide)
    )
    (property "Manufacturer" "Murata" (id 4) (at 115.824 132.461 0)
      (effects (font (size 1.524 1.524)) (justify left) hide)
    )
    (property "MPN" "GRM155R61H104KE14D" (id 5) (at 118.364 132.461 0)
      (effects (font (size 1.524 1.524)) (justify left) hide)
    )
    (property "Val" "100n" (id 6) (at 123.571 131.8322 90)
      (effects (font (size 1.27 1.27)) (justify left))
    )
    (property "License" "Apache-2.0" (id 7) (at 148.844 147.701 0)
      (effects (font (size 1.27 1.27) (thickness 0.15)) (justify left bottom) hide)
    )
    (property "Author" "Antmicro" (id 8) (at 151.384 147.701 0)
      (effects (font (size 1.27 1.27) (thickness 0.15)) (justify left bottom) hide)
    )
    (property "Voltage" "50V" (id 9) (at 153.924 147.701 0)
      (effects (font (size 1.27 1.27)) (justify left bottom) hide)
    )
    (property "Dielectric" "X5R" (id 10) (at 156.464 147.701 0)
      (effects (font (size 1.27 1.27)) (justify left bottom) hide)
    )
    (pin "1")
    (pin "2")
  )

  (symbol (lib_id "sa800u-baseboard-hw:C_100n_0402") (at 109.982 127.635 90) (mirror x) (unit 1)
    (in_bom yes) (on_board yes) (fields_autoplaced)
    (property "Reference" "C69" (id 0) (at 112.649 128.9113 90)
      (effects (font (size 1.524 1.524)) (justify right))
    )
    (property "Value" "C_100n_0402" (id 1) (at 113.792 127.635 0)
      (effects (font (size 1.524 1.524)) hide)
    )
    (property "Footprint" "sa800u-baseboard-hw-footprints:C_0402_1005Metric" (id 2) (at 104.902 132.715 0)
      (effects (font (size 1.524 1.524)) (justify left) hide)
    )
    (property "Datasheet" "https://search.murata.co.jp/Ceramy/image/img/A01X/G101/ENG/GRM155R61H104KE14-01.pdf" (id 3) (at 109.982 127.635 0)
      (effects (font (size 1.27 1.27)) hide)
    )
    (property "Manufacturer" "Murata" (id 4) (at 99.822 132.715 0)
      (effects (font (size 1.524 1.524)) (justify left) hide)
    )
    (property "MPN" "GRM155R61H104KE14D" (id 5) (at 102.362 132.715 0)
      (effects (font (size 1.524 1.524)) (justify left) hide)
    )
    (property "Val" "100n" (id 6) (at 112.649 132.0862 90)
      (effects (font (size 1.27 1.27)) (justify right))
    )
    (property "License" "Apache-2.0" (id 7) (at 132.842 147.955 0)
      (effects (font (size 1.27 1.27) (thickness 0.15)) (justify left bottom) hide)
    )
    (property "Author" "Antmicro" (id 8) (at 135.382 147.955 0)
      (effects (font (size 1.27 1.27) (thickness 0.15)) (justify left bottom) hide)
    )
    (property "Voltage" "50V" (id 9) (at 137.922 147.955 0)
      (effects (font (size 1.27 1.27)) (justify left bottom) hide)
    )
    (property "Dielectric" "X5R" (id 10) (at 140.462 147.955 0)
      (effects (font (size 1.27 1.27)) (justify left bottom) hide)
    )
    (pin "1")
    (pin "2")
  )

  (symbol (lib_id "sa800u-baseboard-hw:GND") (at 125.984 132.461 0) (mirror y) (unit 1)
    (in_bom yes) (on_board yes) (fields_autoplaced)
    (property "Reference" "#PWR044" (id 0) (at 125.984 138.811 0)
      (effects (font (size 1.27 1.27)) hide)
    )
    (property "Value" "GND" (id 1) (at 125.984 136.906 0))
    (property "Footprint" "" (id 2) (at 125.984 132.461 0)
      (effects (font (size 1.27 1.27)) hide)
    )
    (property "Datasheet" "" (id 3) (at 125.984 132.461 0)
      (effects (font (size 1.27 1.27)) hide)
    )
    (property "Author" "Antmicro" (id 4) (at 117.094 140.081 0)
      (effects (font (size 1.27 1.27) (thickness 0.15)) (justify left bottom) hide)
    )
    (property "License" "Apache-2.0" (id 5) (at 117.094 142.621 0)
      (effects (font (size 1.27 1.27) (thickness 0.15)) (justify left bottom) hide)
    )
    (pin "1")
  )

  (symbol (lib_id "sa800u-baseboard-hw:GND") (at 89.662 271.145 0) (unit 1)
    (in_bom yes) (on_board yes) (fields_autoplaced)
    (property "Reference" "#PWR052" (id 0) (at 89.662 277.495 0)
      (effects (font (size 1.27 1.27)) hide)
    )
    (property "Value" "GND" (id 1) (at 89.662 275.59 0))
    (property "Footprint" "" (id 2) (at 89.662 271.145 0)
      (effects (font (size 1.27 1.27)) hide)
    )
    (property "Datasheet" "" (id 3) (at 89.662 271.145 0)
      (effects (font (size 1.27 1.27)) hide)
    )
    (property "Author" "Antmicro" (id 4) (at 98.552 278.765 0)
      (effects (font (size 1.27 1.27) (thickness 0.15)) (justify left bottom) hide)
    )
    (property "License" "Apache-2.0" (id 5) (at 98.552 281.305 0)
      (effects (font (size 1.27 1.27) (thickness 0.15)) (justify left bottom) hide)
    )
    (pin "1")
  )

  (symbol (lib_id "sa800u-baseboard-hw:TXB0104_UQFN") (at 112.395 244.475 0) (mirror y) (unit 1)
    (in_bom yes) (on_board yes) (fields_autoplaced)
    (property "Reference" "U8" (id 0) (at 102.235 236.22 0))
    (property "Value" "TXB0104_UQFN" (id 1) (at 102.235 278.13 0)
      (effects (font (size 1.27 1.27)) hide)
    )
    (property "Footprint" "sa800u-baseboard-hw-footprints:UQFN-12_2x1.7mm_P0.4mm_Texas_RUT" (id 2) (at 114.935 267.335 0)
      (effects (font (size 1.27 1.27)) hide)
    )
    (property "Datasheet" "http://www.ti.com/lit/ds/symlink/txb0104.pdf" (id 3) (at 109.601 242.062 0)
      (effects (font (size 1.27 1.27)) hide)
    )
    (property "Manufacturer" "Texas Instruments" (id 4) (at 122.555 266.065 0)
      (effects (font (size 1.27 1.27)) hide)
    )
    (property "MPN" "TXB0104RUTR" (id 5) (at 102.235 238.76 0))
    (property "Author" "Antmicro" (id 6) (at 76.835 264.795 0)
      (effects (font (size 1.27 1.27) (thickness 0.15)) (justify left bottom) hide)
    )
    (property "License" "Apache-2.0" (id 7) (at 76.835 267.335 0)
      (effects (font (size 1.27 1.27) (thickness 0.15)) (justify left bottom) hide)
    )
    (pin "1")
    (pin "10")
    (pin "11")
    (pin "12")
    (pin "2")
    (pin "3")
    (pin "4")
    (pin "5")
    (pin "6")
    (pin "7")
    (pin "8")
    (pin "9")
  )

  (symbol (lib_id "sa800u-baseboard-hw:GND") (at 109.982 132.715 0) (mirror y) (unit 1)
    (in_bom yes) (on_board yes) (fields_autoplaced)
    (property "Reference" "#PWR054" (id 0) (at 109.982 139.065 0)
      (effects (font (size 1.27 1.27)) hide)
    )
    (property "Value" "GND" (id 1) (at 109.982 137.16 0))
    (property "Footprint" "" (id 2) (at 109.982 132.715 0)
      (effects (font (size 1.27 1.27)) hide)
    )
    (property "Datasheet" "" (id 3) (at 109.982 132.715 0)
      (effects (font (size 1.27 1.27)) hide)
    )
    (property "Author" "Antmicro" (id 4) (at 101.092 140.335 0)
      (effects (font (size 1.27 1.27) (thickness 0.15)) (justify left bottom) hide)
    )
    (property "License" "Apache-2.0" (id 5) (at 101.092 142.875 0)
      (effects (font (size 1.27 1.27) (thickness 0.15)) (justify left bottom) hide)
    )
    (pin "1")
  )

  (symbol (lib_id "sa800u-baseboard-hw:1N4148WS") (at 110.363 119.38 0) (mirror y) (unit 1)
    (in_bom yes) (on_board yes) (fields_autoplaced)
    (property "Reference" "D6" (id 0) (at 106.553 111.76 0)
      (effects (font (size 1.524 1.524)))
    )
    (property "Value" "1N4148WS" (id 1) (at 106.553 115.57 0)
      (effects (font (size 1.524 1.524)))
    )
    (property "Footprint" "sa800u-baseboard-hw-footprints:D_SOD-323F" (id 2) (at 105.283 114.3 0)
      (effects (font (size 1.524 1.524)) (justify left) hide)
    )
    (property "Datasheet" "https://www.onsemi.com/pub/Collateral/1N914BWS-D.pdf" (id 3) (at 105.283 111.76 0)
      (effects (font (size 1.524 1.524)) (justify left) hide)
    )
    (property "MPN" "1N4148WS" (id 4) (at 105.283 106.68 0)
      (effects (font (size 1.524 1.524)) (justify left) hide)
    )
    (property "Manufacturer" "ON Semiconductor" (id 5) (at 105.283 91.44 0)
      (effects (font (size 1.524 1.524)) (justify left) hide)
    )
    (property "Author" "Antmicro" (id 6) (at 88.773 139.7 0)
      (effects (font (size 1.27 1.27) (thickness 0.15)) (justify left bottom) hide)
    )
    (property "License" "Apache-2.0" (id 7) (at 88.773 142.24 0)
      (effects (font (size 1.27 1.27) (thickness 0.15)) (justify left bottom) hide)
    )
    (pin "A")
    (pin "K")
  )

  (symbol (lib_id "sa800u-baseboard-hw:C_100n_0402") (at 54.229 130.81 270) (unit 1)
    (in_bom yes) (on_board yes) (fields_autoplaced)
    (property "Reference" "C67" (id 0) (at 56.896 132.0863 90)
      (effects (font (size 1.524 1.524)) (justify left))
    )
    (property "Value" "C_100n_0402" (id 1) (at 50.419 130.81 0)
      (effects (font (size 1.524 1.524)) hide)
    )
    (property "Footprint" "sa800u-baseboard-hw-footprints:C_0402_1005Metric" (id 2) (at 59.309 135.89 0)
      (effects (font (size 1.524 1.524)) (justify left) hide)
    )
    (property "Datasheet" "https://search.murata.co.jp/Ceramy/image/img/A01X/G101/ENG/GRM155R61H104KE14-01.pdf" (id 3) (at 54.229 130.81 0)
      (effects (font (size 1.27 1.27)) hide)
    )
    (property "Manufacturer" "Murata" (id 4) (at 64.389 135.89 0)
      (effects (font (size 1.524 1.524)) (justify left) hide)
    )
    (property "MPN" "GRM155R61H104KE14D" (id 5) (at 61.849 135.89 0)
      (effects (font (size 1.524 1.524)) (justify left) hide)
    )
    (property "Val" "100n" (id 6) (at 56.896 135.2612 90)
      (effects (font (size 1.27 1.27)) (justify left))
    )
    (property "License" "Apache-2.0" (id 7) (at 31.369 151.13 0)
      (effects (font (size 1.27 1.27) (thickness 0.15)) (justify left bottom) hide)
    )
    (property "Author" "Antmicro" (id 8) (at 28.829 151.13 0)
      (effects (font (size 1.27 1.27) (thickness 0.15)) (justify left bottom) hide)
    )
    (property "Voltage" "50V" (id 9) (at 26.289 151.13 0)
      (effects (font (size 1.27 1.27)) (justify left bottom) hide)
    )
    (property "Dielectric" "X5R" (id 10) (at 23.749 151.13 0)
      (effects (font (size 1.27 1.27)) (justify left bottom) hide)
    )
    (pin "1")
    (pin "2")
  )

  (symbol (lib_id "sa800u-baseboard-hw:GND") (at 54.229 135.89 0) (unit 1)
    (in_bom yes) (on_board yes) (fields_autoplaced)
    (property "Reference" "#PWR051" (id 0) (at 54.229 142.24 0)
      (effects (font (size 1.27 1.27)) hide)
    )
    (property "Value" "GND" (id 1) (at 54.229 140.335 0))
    (property "Footprint" "" (id 2) (at 54.229 135.89 0)
      (effects (font (size 1.27 1.27)) hide)
    )
    (property "Datasheet" "" (id 3) (at 54.229 135.89 0)
      (effects (font (size 1.27 1.27)) hide)
    )
    (property "Author" "Antmicro" (id 4) (at 63.119 143.51 0)
      (effects (font (size 1.27 1.27) (thickness 0.15)) (justify left bottom) hide)
    )
    (property "License" "Apache-2.0" (id 5) (at 63.119 146.05 0)
      (effects (font (size 1.27 1.27) (thickness 0.15)) (justify left bottom) hide)
    )
    (pin "1")
  )

  (symbol (lib_id "sa800u-baseboard-hw:GND") (at 91.44 165.862 0) (unit 1)
    (in_bom yes) (on_board yes) (fields_autoplaced)
    (property "Reference" "#PWR050" (id 0) (at 91.44 172.212 0)
      (effects (font (size 1.27 1.27)) hide)
    )
    (property "Value" "GND" (id 1) (at 91.44 170.942 0))
    (property "Footprint" "" (id 2) (at 91.44 165.862 0)
      (effects (font (size 1.27 1.27)) hide)
    )
    (property "Datasheet" "" (id 3) (at 91.44 165.862 0)
      (effects (font (size 1.27 1.27)) hide)
    )
    (property "Author" "Antmicro" (id 4) (at 100.33 173.482 0)
      (effects (font (size 1.27 1.27) (thickness 0.15)) (justify left bottom) hide)
    )
    (property "License" "Apache-2.0" (id 5) (at 100.33 176.022 0)
      (effects (font (size 1.27 1.27) (thickness 0.15)) (justify left bottom) hide)
    )
    (pin "1")
  )

  (symbol (lib_id "sa800u-baseboard-hw:PWR_FLAG") (at 118.11 190.5 0) (unit 1)
    (in_bom yes) (on_board yes) (fields_autoplaced)
    (property "Reference" "#FLG010" (id 0) (at 118.11 188.595 0)
      (effects (font (size 1.27 1.27)) hide)
    )
    (property "Value" "PWR_FLAG" (id 1) (at 118.11 185.42 0))
    (property "Footprint" "" (id 2) (at 118.11 190.5 0)
      (effects (font (size 1.27 1.27)) hide)
    )
    (property "Datasheet" "~" (id 3) (at 118.11 190.5 0)
      (effects (font (size 1.27 1.27)) hide)
    )
    (pin "1")
  )

  (symbol (lib_id "sa800u-baseboard-hw:GND") (at 269.875 261.62 0) (unit 1)
    (in_bom yes) (on_board yes) (fields_autoplaced)
    (property "Reference" "#PWR069" (id 0) (at 269.875 267.97 0)
      (effects (font (size 1.27 1.27)) hide)
    )
    (property "Value" "GND" (id 1) (at 267.97 262.8899 0)
      (effects (font (size 1.27 1.27)) (justify right))
    )
    (property "Footprint" "" (id 2) (at 269.875 261.62 0)
      (effects (font (size 1.27 1.27)) hide)
    )
    (property "Datasheet" "" (id 3) (at 269.875 261.62 0)
      (effects (font (size 1.27 1.27)) hide)
    )
    (property "Author" "Antmicro" (id 4) (at 278.765 269.24 0)
      (effects (font (size 1.27 1.27) (thickness 0.15)) (justify left bottom) hide)
    )
    (property "License" "Apache-2.0" (id 5) (at 278.765 271.78 0)
      (effects (font (size 1.27 1.27) (thickness 0.15)) (justify left bottom) hide)
    )
    (pin "1")
  )

  (symbol (lib_id "sa800u-baseboard-hw:GND") (at 316.23 97.79 0) (unit 1)
    (in_bom yes) (on_board yes) (fields_autoplaced)
    (property "Reference" "#PWR071" (id 0) (at 316.23 104.14 0)
      (effects (font (size 1.27 1.27)) hide)
    )
    (property "Value" "GND" (id 1) (at 316.23 102.87 0))
    (property "Footprint" "" (id 2) (at 316.23 97.79 0)
      (effects (font (size 1.27 1.27)) hide)
    )
    (property "Datasheet" "" (id 3) (at 316.23 97.79 0)
      (effects (font (size 1.27 1.27)) hide)
    )
    (property "Author" "Antmicro" (id 4) (at 325.12 105.41 0)
      (effects (font (size 1.27 1.27) (thickness 0.15)) (justify left bottom) hide)
    )
    (property "License" "Apache-2.0" (id 5) (at 325.12 107.95 0)
      (effects (font (size 1.27 1.27) (thickness 0.15)) (justify left bottom) hide)
    )
    (pin "1")
  )

  (symbol (lib_id "sa800u-baseboard-hw:GND") (at 346.71 97.79 0) (unit 1)
    (in_bom yes) (on_board yes) (fields_autoplaced)
    (property "Reference" "#PWR077" (id 0) (at 346.71 104.14 0)
      (effects (font (size 1.27 1.27)) hide)
    )
    (property "Value" "GND" (id 1) (at 346.71 102.87 0))
    (property "Footprint" "" (id 2) (at 346.71 97.79 0)
      (effects (font (size 1.27 1.27)) hide)
    )
    (property "Datasheet" "" (id 3) (at 346.71 97.79 0)
      (effects (font (size 1.27 1.27)) hide)
    )
    (property "Author" "Antmicro" (id 4) (at 355.6 105.41 0)
      (effects (font (size 1.27 1.27) (thickness 0.15)) (justify left bottom) hide)
    )
    (property "License" "Apache-2.0" (id 5) (at 355.6 107.95 0)
      (effects (font (size 1.27 1.27) (thickness 0.15)) (justify left bottom) hide)
    )
    (pin "1")
  )

  (symbol (lib_id "sa800u-baseboard-hw:GND") (at 177.165 80.645 0) (unit 1)
    (in_bom yes) (on_board yes) (fields_autoplaced)
    (property "Reference" "#PWR059" (id 0) (at 177.165 86.995 0)
      (effects (font (size 1.27 1.27)) hide)
    )
    (property "Value" "GND" (id 1) (at 175.26 81.9149 0)
      (effects (font (size 1.27 1.27)) (justify right))
    )
    (property "Footprint" "" (id 2) (at 177.165 80.645 0)
      (effects (font (size 1.27 1.27)) hide)
    )
    (property "Datasheet" "" (id 3) (at 177.165 80.645 0)
      (effects (font (size 1.27 1.27)) hide)
    )
    (property "Author" "Antmicro" (id 4) (at 186.055 88.265 0)
      (effects (font (size 1.27 1.27) (thickness 0.15)) (justify left bottom) hide)
    )
    (property "License" "Apache-2.0" (id 5) (at 186.055 90.805 0)
      (effects (font (size 1.27 1.27) (thickness 0.15)) (justify left bottom) hide)
    )
    (pin "1")
  )

  (symbol (lib_id "sa800u-baseboard-hw:GND") (at 149.86 80.645 0) (unit 1)
    (in_bom yes) (on_board yes) (fields_autoplaced)
    (property "Reference" "#PWR057" (id 0) (at 149.86 86.995 0)
      (effects (font (size 1.27 1.27)) hide)
    )
    (property "Value" "GND" (id 1) (at 147.32 81.9149 0)
      (effects (font (size 1.27 1.27)) (justify right))
    )
    (property "Footprint" "" (id 2) (at 149.86 80.645 0)
      (effects (font (size 1.27 1.27)) hide)
    )
    (property "Datasheet" "" (id 3) (at 149.86 80.645 0)
      (effects (font (size 1.27 1.27)) hide)
    )
    (property "Author" "Antmicro" (id 4) (at 158.75 88.265 0)
      (effects (font (size 1.27 1.27) (thickness 0.15)) (justify left bottom) hide)
    )
    (property "License" "Apache-2.0" (id 5) (at 158.75 90.805 0)
      (effects (font (size 1.27 1.27) (thickness 0.15)) (justify left bottom) hide)
    )
    (pin "1")
  )

  (symbol (lib_id "sa800u-baseboard-hw:PWR_FLAG") (at 113.665 236.22 0) (unit 1)
    (in_bom yes) (on_board yes)
    (property "Reference" "#FLG0108" (id 0) (at 113.665 234.315 0)
      (effects (font (size 1.27 1.27)) hide)
    )
    (property "Value" "PWR_FLAG" (id 1) (at 113.665 232.664 0))
    (property "Footprint" "" (id 2) (at 113.665 236.22 0)
      (effects (font (size 1.27 1.27)) hide)
    )
    (property "Datasheet" "~" (id 3) (at 113.665 236.22 0)
      (effects (font (size 1.27 1.27)) hide)
    )
    (pin "1")
  )
)
